# Barreleye-G2_Tri-mode BPX24-DVT-X01-SKU-BOM-X07-20171222_Final.xls.xlsx — PWA BOM (bom)
| FOXCONN TECHNOLOGY GROUP |  |  |  |  |  |  |  |  |  |  |  |  |  |  |  |  |  |  |  |  |  |  |  |
| BILL OF MATERIAL |  |  |  |  |  |  |  |  |  |  |  |  |  |  |  |  |  |  |  |  |  |  |  |
| REV OF  BOM | X07 | CUSTOMER |  | <name> |  | CUSTOMER P/N |  | PWA P/N： | PWA DESCRIPTION |  |  |  |  |  |  |  | PRODUCT CODE |  |  | PWA  REV | X01 | DATE | 43091 |
| Sourcing (Single/Sole/Multi) | Critical Commodity (Y or N) | Component Class (1, 2, other) | Customer PSL (Y or N) | Line Item | Item Number | Foxconn P/N | Customer P/N | Part Description | Manufacturer  Full Name | Manufacturer  Part Number | On-Board build status | SKU1 | SKU2 | SKU3 | Qty | RoHS Status | Location | CC Qual Build: | Qual by (Customer / ODM ?) | The Date of Change Part or Add 2nd Source | Configuration Identifier | Customer Comments | ODM Comments |
| Multi |  |  |  | 1 | 1 | 0101FGA00-000-G |  | PCB,Zaius-Tri-mode BPX24 DVT-X01,OSP,Blu,22L,21.122*3.470,G | GOLD CIRCUIT ELECTRONICS LTD. | 0101FGA00-000-G |  | 1 | 2 | 3 | 1 | G | PCB |  |  |  |  |  |  |
|  |  |  |  |  | 1 | 0101FGA00-000-G |  | PCB,Zaius-Tri-mode BPX24 DVT-X01,OSP,Blu,22L,21.122*3.470,G | ZHUHAI FOUNDER PRINTED CIRCUIT BOARD（HK） DEVELOPMENT LIMITED | 0101FGA00-000-G |  | 1 | 2 | 3 |  | G |  |  |  |  |  |  |  |
| Multi | Y |  | N | 2 | 2 | 62111EC00-021-G |  | ECAP,680uF,+/-20%,16V,105℃,G,SMD10*10,ESR<=80mOhm | NIPPON CHEMI-CON CORPORATION | EMZA160ADA681MJA0G | EVT | 1 |  |  | 1 | G | CE1 |  |  |  |  |  |  |
|  |  |  |  |  | 2 | 62110EH00-024-G |  | ECAP,680uF,+/-20%,16V,105_x0003_,G,SMD10X10.2,ESR<=80mOhm | PANASONIC INDUSTRIAL CO.,LTD. | EEEFK1C681P |  |  | 2 |  |  | G |  |  |  |  |  |  |  |
|  |  |  |  |  | 2 | 62111H200-018-G |  | ECAP,680uF,+/-20%,16V,105_x0003_,G,SMD10X10.5,ESR<=80mOhm | RUBYCON CORP. | 16TZV680M10X10.5 |  |  |  | 3 |  | G |  |  |  |  |  |  |  |
| Multi | Y | 2 | Y(3) | 3 | 3 | 620101T02-015-G | - | CAP,100nF,+/-10%,X7R,16V,G,SMD0402 | MURATA ELEC. NORTH AMERICA | GRM155R71C104K | EVT | 1 | 2 | 3 | 145 | G | PSTC1,PFTC1,PETC1,C1,C2,C6,C8,C9,PSRC10,C10,C15,C19,C119,C123,C125,C129,C155,C159,C161,C165,C167,C171,C173,C177,C179,C183,C185,C189,C191,C192,C193,C194,C196,C198,C201,C207,C216,C217,C224,C249,C253,C255,C259,C261,C265,C267,C271,C273,C277,C279,C283,C285,C289,C291,C295,C297,C301,C303,C307,C309,C313,C315,C319,C321,C325,C327,C331,C333,C337,C339,C343,C397,C2101,C2102,C2103,C2104,C2105,C2106,C2107,C2108,C2109,C2110,C2111,C2112,C2113,C2114,C2115,C2116,C2117,C2118,C2119,C2120,C2121,C2122,C2123,C2124,C2125,C2126,C2127,C2128,C2129,C2130,C2131,C2132,C2133,C2134,C2135,C2136,C2137,C2138,C2139,C2140,C2141,C2143,C2145,C2147,C2149,C2169,C2171,C2176,C2177,C2178,C2232,C2233,C2234,C2235,C2237,C2239,C2240,C2241,C2242,C2254,C2255,C2256,C2259,C2260,C2261,C2262,C2263,C2264,C2265,C2266,C2270,C2271,C2272 |  |  |  |  |  |  |
|  |  |  |  |  | 3 | 620101T00-012-G |  | CAP,100nF,+/-10%,X7R,16V,G,SMD0402 | WALSIN TECHNOLOGY CORPORATION | 0402B104K160CT |  | 1 | 2 | 3 |  | G |  |  |  |  |  |  |  |
|  |  |  |  |  | 3 | 620101T00-026-G |  | CAP,100nF,+/-10%,X7R,16V,G,SMD0402 | SAMSUNG SEMICONDUCTOR | CL05B104KO5NNNC |  | 1 | 2 | 3 |  | G |  |  |  |  |  |  |  |
|  |  |  |  |  | 3 | 620101T00-015-G |  | CAP,100nF,+/-10%,X7R,16V,G,SMD0402 | MURATA ELEC. NORTH AMERICA | GRM155R71C104KA88D |  | 1 | 2 | 3 |  | G |  |  |  |  |  |  |  |
| Multi | Y | 2 | N | 4 | 4 | 620100A00-015-G | - | CAP,10uF,+/-10%,X5R,16V,G,SMD1206 | MURATA ELEC. NORTH AMERICA | GRM31CR61C106K |  | 1 | 2 | 3 | 30 | G | C3,C4,C5,C7,C120,C128,C158,C164,C170,C176,C182,C188,C252,C258,C264,C270,C276,C282,C288,C294,C300,C306,C312,C318,C324,C330,C336,C342,C2236,C2238 |  |  |  |  |  |  |
|  |  |  |  |  | 4 | 620100A00-026-G |  | CAP,10uF,+/-10%,X5R,16V,G,SMD1206 | SAMSUNG SEMICONDUCTOR | CL31A106KOHNNNE | EVT | 1 | 2 | 3 |  | G |  |  |  |  |  |  |  |
|  |  |  |  |  | 4 | 620100A03-023-G |  | CAP,10uF,+/-10%,X5R,16V,G,SMD1206 | TAIYO ELECTRIC IND.CO.LTD | EMK316BJ106KL-T |  | 1 | 2 | 3 |  | G |  |  |  |  |  |  |  |
|  |  |  |  |  | 4 | 620100A00-012-G |  | CAP,10uF,+/-10%,X5R,16V,G,SMD1206 | WALSIN TECHNOLOGY CORPORATION | 1206X106K160CT |  | 1 | 2 | 3 |  | G |  |  |  |  |  |  |  |
|  |  |  |  |  | 4 | 620100A00-011-G |  | CAP,10uF,+/-10%,X5R,16V,G,SMD1206 | YAGEO CORPORATION COMPONENT | CC1206KKX5R7BB106 |  | 1 | 2 | 3 |  | G |  |  |  |  |  |  |  |
| Multi | ND | ND | N | 5 | 5 | 620117N00-015-G | - | CAP,22uF,+/-10%,X5R,16V,G,SMD1206 | MURATA ELEC. NORTH AMERICA | GRM31CR61C226K | EVT | 1 | 2 | 3 | 48 | G | C121,C122,C126,C130,C156,C160,C162,C166,C168,C172,C174,C178,C180,C184,C186,C190,C250,C254,C256,C260,C262,C266,C268,C272,C274,C278,C280,C284,C286,C290,C292,C296,C298,C302,C304,C308,C310,C314,C316,C320,C322,C326,C328,C332,C334,C338,C340,C344 |  |  |  |  |  |  |
|  |  |  |  |  | 5 | 620117N00-023-G |  | CAP,22uF,+/-10%,X5R,16V,G,SMD1206 | TAIYO ELECTRIC IND.CO.LTD | EMK316BJ226KL-T |  | 1 | 2 | 3 |  | G |  |  |  |  |  |  |  |
|  |  |  |  |  | 5 | 620117N01-026-G |  | CAP,22uF,+/-10%,X5R,16V,G,SMD1206 | SAMSUNG SEMICONDUCTOR | CL31A226KOHNNNE |  | 1 | 2 | 3 |  | G |  |  |  |  |  |  |  |
| Multi | Y | 2 | N | 6 | 6 | 620108H00-015-G | - | CAP,22uF,+/-20%,X5R,6.3V,G,SMD0805 | MURATA ELEC. NORTH AMERICA | GRM21BR60J226M | EVT | 1 | 2 | 3 | 24 | G | C124,C127,C157,C163,C169,C175,C181,C187,C251,C257,C263,C269,C275,C281,C287,C293,C299,C305,C311,C317,C323,C329,C335,C341 |  |  |  |  |  |  |
|  |  |  |  |  | 6 | 620108H04-023-G |  | CAP,22uF,+/-20%,X5R,6.3V,G,SMD0805 | TAIYO ELECTRIC IND.CO.LTD | JMK212BJ226MG-T |  | 1 | 2 | 3 |  | G |  |  |  |  |  |  |  |
|  |  |  |  |  | 6 | 620108H00-026-G |  | CAP,22uF,+/-20%,X5R,6.3V,G,SMD0805 | SAMSUNG SEMICONDUCTOR | CL21A226MQQNNNE | EVT | 1 | 2 | 3 |  | G |  |  |  |  |  |  |  |
|  |  |  |  |  | 6 | 620108H00-011-G |  | CAP,22uF,+/-20%,X5R,6.3V,G,SMD0805 | YAGEO CORPORATION COMPONENT | CC0805MKX5R5BB226 |  | 1 | 2 | 3 |  | G |  |  |  |  |  |  |  |
| Multi | ND | ND | N | 7 | 7 | 62011AM00-015-G |  | CAP,6.8nF,+/-10%,X7R,50V,G,SMD0402 | MURATA ELEC. NORTH AMERICA | GRM155R71H682K | EVT | 1 | 2 | 3 | 1 | G | C195 |  |  |  |  |  |  |
|  |  |  |  |  | 7 | 62011AM00-012-G |  | CAP,6.8nF,+/-10%,X7R,50V,G,SMD0402 | WALSIN TECHNOLOGY CORPORATION | 0402B682K500CT |  | 1 | 2 | 3 |  | G |  |  |  |  |  |  |  |
|  |  |  |  |  | 7 | 62011AM00-026-G |  | CAP,6.8nF,+/-10%,X7R,50V,G,SMD0402 | SAMSUNG SEMICONDUCTOR | CL05B682KB5NNNC |  | 1 | 2 | 3 |  | G |  |  |  |  |  |  |  |
| Multi | ND | ND | N | 8 | 8 | 620105E00-015-G |  | CAP,1uF,+/-10%,X7R,10V,G,SMD0603 | MURATA ELEC. NORTH AMERICA | GRM188R71A105K | EVT | 1 | 2 | 3 | 2 | G | C197,C215 |  |  |  |  |  |  |
|  |  |  |  |  | 8 | 620105E00-012-G |  | CAP,1uF,+/-10%,X7R,10V,G,SMD0603 | WALSIN TECHNOLOGY CORPORATION | 0603B105K100CT |  | 1 | 2 | 3 |  | G |  |  |  |  |  |  |  |
|  |  |  |  |  | 8 | 620105E00-011-G |  | CAP,1uF,+/-10%,X7R,10V,G,SMD0603 | YAGEO CORPORATION COMPONENT | CC0603KRX7R6BB105 |  | 1 | 2 | 3 |  | G |  |  |  |  |  |  |  |
|  |  |  |  |  | 8 | 620105E00-026-G |  | CAP,1uF,+/-10%,X7R,10V,G,SMD0603 | SAMSUNG SEMICONDUCTOR | CL10B105KP8NNNC |  | 1 | 2 | 3 |  | G |  |  |  |  |  |  |  |
|  |  |  |  |  | 8 | 620105E01-023-G |  | CAP,1uF,+/-10%,X7R,10V,G,SMD0603 | TAIYO ELECTRIC IND.CO.LTD | LMK107B7105KA-T |  | 1 | 2 | 3 |  | G |  |  |  |  |  |  |  |
| Multi | Y | 2 | N | 9 | 9 | 620103600-015-G | - | CAP,10nF,+/-10%,X7R,25V,G,SMD0402 | MURATA ELEC. NORTH AMERICA | GRM155R71E103K | EVT | 1 | 2 | 3 | 14 | G | C199,C202,C203,C204,C205,C218,C219,C220,C221,C222,C2243,C2244,C2251,C2252 |  |  |  |  |  |  |
|  |  |  |  |  | 9 | 620103600-012-G |  | CAP,10nF,+/-10%,X7R,25V,G,SMD0402 | WALSIN TECHNOLOGY CORPORATION | 0402B103K250CT |  | 1 | 2 | 3 |  | G |  |  |  |  |  |  |  |
|  |  |  |  |  | 9 | 620103600-011-G |  | CAP,10nF,+/-10%,X7R,25V,G,SMD0402 | YAGEO CORPORATION COMPONENT | CC0402KRX7R8BB103 |  | 1 | 2 | 3 |  | G |  |  |  |  |  |  |  |
|  |  |  |  |  | 9 | 620103600-026-G |  | CAP,10nF,+/-10%,X7R,25V,G,SMD0402 | SAMSUNG SEMICONDUCTOR | CL05B103KA5NNNC |  | 1 | 2 | 3 |  | G |  |  |  |  |  |  |  |
|  |  |  |  |  | 9 | 620103601-023-G |  | CAP,10nF,+/-10%,X7R,25V,G,SMD0402 | TAIYO ELECTRIC IND.CO.LTD | TMK105B7103KV-F |  | 1 | 2 | 3 |  | G |  |  |  |  |  |  |  |
| Multi | ND | ND | N | 10 | 10 | 62010L000-015-G | - | CAP,10uF,+/-20%,X5R,6.3V,G,SMD0603 | MURATA ELEC. NORTH AMERICA | GRM188R60J106M |  | 1 | 2 | 3 | 2 | G | C200,C214 |  |  |  |  |  |  |
|  |  |  |  |  | 10 | 62010L000-023-G |  | CAP,10uF,+/-20%,X5R,6.3V,G,SMD0603 | TAIYO ELECTRIC IND.CO.LTD | JMK107BJ106MA-T |  | 1 | 2 | 3 |  | G |  |  |  |  |  |  |  |
|  |  |  |  |  | 10 | 62010L000-012-G |  | CAP,10uF,+/-20%,X5R,6.3V,G,SMD0603 | WALSIN TECHNOLOGY CORPORATION | 0603X106M6R3CT | EVT | 1 | 2 | 3 |  | G |  |  |  |  |  |  |  |
|  |  |  |  |  | 10 | 62010L000-026-G |  | CAP,10uF,+/-20%,X5R,6.3V,G,SMD0603 | SAMSUNG SEMICONDUCTOR | CL10A106MQ8NNNC |  | 1 | 2 | 3 |  | G |  |  |  |  |  |  |  |
|  |  |  |  |  | 10 | 62010L000-011-G |  | CAP,10uF,+/-20%,X5R,6.3V,G,SMD0603 | YAGEO CORPORATION COMPONENT | CC0603MRX5R5BB106 |  | 1 | 2 | 3 |  | G |  |  |  |  |  |  |  |
| Multi | ND | ND | N | 11 | 11 | 62011NF01-015-G |  | CAP,2.2uF,+/-10%,X7R,25V,G,SMD0805 | MURATA ELEC. NORTH AMERICA | GRM21BR71E225K | EVT | 1 | 2 | 3 | 2 | G | C206,C223 |  |  |  |  |  |  |
|  |  |  |  |  | 11 | 62011NF00-026-G |  | CAP,2.2uF,+/-10%,X7R,25V,G,SMD0805 | SAMSUNG SEMICONDUCTOR | CL21B225KAFNNNE |  | 1 | 2 | 3 |  | G |  |  |  |  |  |  |  |
|  |  |  |  |  | 11 | 62011NF00-023-G |  | CAP,2.2uF,+/-10%,X7R,25V,G,SMD0805 | TAIYO ELECTRIC IND.CO.LTD | TMK212B7225KG-TR |  | 1 | 2 | 3 |  | G |  |  |  |  |  |  |  |
| Multi | ND | ND | Y(1) | 12 | 12 | 620114000-015-G |  | CAP,10uF,+/-10%,X5R,16V,G,SMD0805 | MURATA ELEC. NORTH AMERICA | GRM21BR61C106K | EVT | 1 | 2 | 3 | 3 | G | C1946,C2081,C2253 |  |  |  |  |  |  |
|  |  |  |  |  | 12 | 620114005-023-G |  | CAP,10uF,+/-10%,X5R,16V,G,SMD0805 | TAIYO ELECTRIC IND.CO.LTD | EMK212ABJ106KG-T |  | 1 | 2 | 3 |  | G |  |  |  |  |  |  |  |
|  |  |  |  |  | 12 | 620114000-026-G |  | CAP,10uF,+/-10%,X5R,16V,G,SMD0805 | SAMSUNG SEMICONDUCTOR | CL21A106KOQNNNE |  | 1 | 2 | 3 |  | G |  |  |  |  |  |  |  |
|  |  |  |  |  | 12 | 620114000-012-G |  | CAP,10uF,+/-10%,X5R,16V,G,SMD0805 | WALSIN TECHNOLOGY CORPORATION | 0805X106K160CT |  | 1 | 2 | 3 |  | G |  |  |  |  |  |  |  |
| Multi | Y | 2 | N | 13 | 13 | 620105400-015-G |  | CAP,1uF,+/-10%,X7R,16V,G,SMD0603 | MURATA ELEC. NORTH AMERICA | GRM188R71C105K |  | 1 | 2 | 3 | 10 | G | C1950,C2080,C2245,C2246,C2247,C2248,C2249,C2250,C2257,C2258 |  |  |  |  |  |  |
|  |  |  |  |  | 13 | 620105400-012-G |  | CAP,1uF,+/-10%,X7R,16V,G,SMD0603 | WALSIN TECHNOLOGY CORPORATION | 0603B105K160CT | EVT | 1 | 2 | 3 |  | G |  |  |  |  |  |  |  |
|  |  |  |  |  | 13 | 620105400-011-G |  | CAP,1uF,+/-10%,X7R,16V,G,SMD0603 | YAGEO CORPORATION COMPONENT | CC0603KRX7R7BB105 |  | 1 | 2 | 3 |  | G |  |  |  |  |  |  |  |
|  |  |  |  |  | 13 | 620105400-026-G |  | CAP,1uF,+/-10%,X7R,16V,G,SMD0603 | SAMSUNG SEMICONDUCTOR | CL10B105KO8NNNC |  | 1 | 2 | 3 |  | G |  |  |  |  |  |  |  |
|  |  |  |  |  | 13 | 620105400-023-G |  | CAP,1uF,+/-10%,X7R,16V,G,SMD0603 | TAIYO ELECTRIC IND.CO.LTD | EMK107B7105KA-T |  | 1 | 2 | 3 |  | G |  |  |  |  |  |  |  |
| Multi | ND | ND | Y(1) | 14 | 14 | 62011LU00-015-G | - | CAP,100nF,+/-10%,X5R,16V,G,SMD0402 | MURATA ELEC. NORTH AMERICA | GRM155R61C104KA88D | EVT | 1 | 2 | 3 | 18 | G | C2198,C2208,C2209,C2210,C2211,C2212,C2213,C2214,C2215,C2216,C2217,C2218,C2219,C2220,C2221,C2222,C2223,C2224 |  |  |  |  |  |  |
|  |  |  |  |  | 14 | 620100300-023-G |  | CAP,100nF,+/-10%,X5R,16V,G,SMD0402 | TAIYO | EMK105BJ104KV-F |  | 1 | 2 | 3 |  | G |  |  |  |  |  |  |  |
|  |  |  |  |  | 14 | 620100300-026-G |  | CAP,100nF,+/-10%,X5R,16V,G,SMD0402 | SAMSUNG SEMICONDUCTOR | CL05A104KO5NNNC |  | 1 | 2 | 3 |  | G |  |  |  |  |  |  |  |
|  |  |  |  |  | 14 | 620100300-012-G |  | CAP,100nF,+/-10%,X5R,16V,G,SMD0402 | WALSIN TECHNOLOGY CORPORATION | 0402X104K160CT |  | 1 | 2 | 3 |  | G |  |  |  |  |  |  |  |
| Multi | ND | ND | Y(1) | 15 | 15 | 620109S00-023-G |  | CAP,4.7uF,+/-10%,X7R,10V,G,SMD0805 | TAIYO ELECTRIC IND.CO.LTD | LMK212B7475KG-T | EVT | 1 | 2 | 3 | 1 | G | C2231 |  |  |  |  |  |  |
|  |  |  |  |  | 15 | 620109S00-026-G |  | CAP,4.7uF,+/-10%,X7R,10V,G,SMD0805 | SAMSUNG SEMICONDUCTOR | CL21B475KPFNNNE |  | 1 | 2 | 3 |  | G |  |  |  |  |  |  |  |
|  |  |  |  |  | 15 | 620109S00-015-G |  | CAP,4.7uF,+/-10%,X7R,10V,G,SMD0805 | MURATA ELEC. NORTH AMERICA | GRM21BR71A475K |  | 1 | 2 | 3 |  | G |  |  |  |  |  |  |  |
| Multi | ND | ND | Y(3) | 16 | 16 | 62012UW00-015-G | - | CAP,6.8pF,+/-0.05pF,NPO(C0G),25V,G,SMD0402 | MURATA ELEC. NORTH AMERICA | GRM1555C1E6R8WA01D | EVT | 1 | 2 | 3 | 2 | G | C2268,C2269 |  |  |  |  |  |  |
|  |  |  |  |  | 16 | 62012UW00-012-G |  | CAP,6.8pF,+/-0.05pF,NPO(C0G),25V,G,SMD0402 | WALSIN TECHNOLOGY CORPORATION | 0402N6R8A250CT |  | 1 | 2 | 3 |  | G |  |  |  |  |  |  |  |
| Multi | N | 1 | N | 17 | 17 | 52110LN00-289-G |  | LED,Gre,LTST-C191KGKT,2.4V,30mA,G,SMD0603 | LITE-ON TECHNOLOGY CORPORATION | LTST-C191KGKT | EVT | 1 |  | 3 | 24 | G | LED37,LED39,LED49,LED51,LED53,LED55,LED57,LED59,LED61,LED63,LED65,LED67,LED69,LED71,LED73,LED75,LED77,LED79,LED81,LED83,LED85,LED87,LED89,LED91 |  |  |  |  |  |  |
|  |  |  |  |  | 17 | 52110K100-030-G |  | LED LAMP,SML-512MWT86,Green,40mcd@If=20mA,N/A,5V,25mA,N/A,,SMD0603,2P,G | ROHM CORPORATION | SML-512MWT86 |  |  | 2 |  |  | G |  |  |  |  |  |  |  |
| Multi | N | 1 | N | 18 | 18 | 52110A800-289-G | 6W731 | LED,Gre/Yel,LTST-C195KGJSKT,2.4V,30mA,G,SMD | LITE-ON TECHNOLOGY CORPORATION | LTST-C195KGJSKT | EVT | 1 |  | 3 | 24 | G | LED38,LED40,LED50,LED52,LED54,LED56,LED58,LED60,LED62,LED64,LED66,LED68,LED70,LED72,LED74,LED76,LED78,LED80,LED82,LED84,LED86,LED88,LED90,LED92 |  |  |  |  |  |  |
|  |  |  |  |  | 18 | 52110QV00-326-G |  | LED,Yel/Yel Gre,19-223/Y2G6C-A01/2T,2.4V,25mA,G,SMD | EVERLIGHT ELECTRONICS COMPANY,LTD. | 19-223/Y2G6C-A01/2T |  |  | 2 |  |  | G |  |  |  |  |  |  |  |
| Multi | N | ND | N | 19 | 19 | 720101900-015-G | - | FB,60 Ohm@100MHz,+/-25%,3A,25mOhm,G,SMD0805 | MURATA ELEC. NORTH AMERICA | BLM21PG600SN1D |  | 1 |  | 3 | 1 | G | L1 |  |  |  |  |  |  |
|  |  |  |  |  | 19 | 720101900-026-G |  | FB,60 Ohm@100MHz,+/-25%,3A,25mOhm,G,SMD0805 | SAMSUNG SEMICONDUCTOR | CIC21P600NE | EVT |  |  |  |  | G |  |  |  |  |  |  |  |
|  |  |  |  |  | 19 | 720104100-074-G |  | FB,60 Ohm@100MHz,+/-25%,3A,30mOhm,G,SMD0805 | CHILISIN ELECTRONICS CORP. | PBY201209T-600Y-N |  |  | 2 |  |  | G |  |  |  |  |  |  |  |
| Multi | N | ND | N | 20 | 20 | 72010JY00-015-G |  | FB,330 Ohm@100MHz,+/-25%,1.5A,70mOhm,G,SMD0603 | MURATA ELEC. NORTH AMERICA | BLM18SG331TN1D | EVT | 1 |  | 3 | 2 | G | L2,L4 |  |  |  |  |  |  |
|  |  |  |  |  | 20 | 72010JB00-016-G |  | FB,330 Ohm@100MHz,+/-25%,1.5A,G,80mOhm,SMD0603 | TDK ELECTRONICS EUROPE GMBH | MPZ1608S331AT |  |  | 2 |  |  | G |  |  |  |  |  |  |  |
| Multi | ND | ND | N | 21 | 21 | 72010FB01-016-G |  | FB,600 Ohm@100MHz,+/-25%,1A,150mOhm,G,SMD0603 | TDK ELECTRONICS EUROPE GMBH | MPZ1608S601AT | EVT | 1 |  |  | 2 | G | L6,L28 |  |  |  |  |  |  |
|  |  |  |  |  | 21 | 72010KF01-015-G |  | FB,600 Ohm@100MHz,+/-25%,1.3A,150mOhm,G,SMD0603 | MURATA ELEC. NORTH AMERICA | BLM18KG601SN1D |  |  | 2 |  |  | G |  |  |  |  |  |  |  |
|  |  |  |  |  | 21 | 72010WP00-059-G |  | FB,600 Ohm@100MHz,+/-25%,1.5A,150mOhm,G,SMD0603 | TAI-TECH Advanced Electronics Co., Ltd. | HCB1608KF-601T15 |  |  |  | 3 |  | G |  |  |  |  |  |  |  |
|  |  |  |  |  | 21 | 72010KF00-174-G |  | FB,600 Ohm@100MHz,+/-25%,1.3A,150mOhm,G,SMD0603 | MAX ECHO TECHNOLOGIES CORP | ACMS160808A601 1.3A |  |  |  |  |  | G |  |  |  |  |  |  |  |
| Multi | ND | ND | Y(2) | 22 | 22 | 720102001-015-G | - | FB,30 Ohm@100MHz,+/-25%,3A,15mOhm,G,SMD0805 | MURATA ELEC. NORTH AMERICA | BLM21PG300SN1D | EVT | 1 |  | 3 | 1 | G | L30 |  |  |  |  |  |  |
|  |  |  |  |  | 22 | 720102002-129-G |  | FB,30 Ohm@100MHz,+/-25%,3A,15mOhm,G,SMD0805 | MAG.LAYERS, SCIENTIFIC-TECHNICS (KUNSHAN) CO., LTD. | GMLB-201209-0030P-N8-RM |  |  | 2 |  |  | G |  |  |  |  |  |  |  |
| Multi | Y | ND | Y(2) | 23 | 23 | 720101L00-015-G | R8955 | FB,600 Ohm@100MHz,+/-25%,200mA,500mOhm,G,SMD0603 | MURATA ELEC. NORTH AMERICA | BLM18AG601SN1D | EVT | 1 |  |  | 1 | G | L31 |  |  |  |  |  |  |
|  |  |  |  |  | 23 | 720101L00-074-G |  | FB,600Ohm@100MHz,+/-25%,200mA,500mOhm,SMD0603,G | CHILISIN ELECTRONICS CORP. | SBK160808T-601Y-N |  |  |  | 3 |  | G |  |  |  |  |  |  |  |
|  |  |  |  |  | 23 | 720105E04-016-G |  | FB,600Ohm@100MHz,+/-25%,500mA,400mOhm,SMD0603,G | TDK ELECTRONICS EUROPE GMBH | MMZ1608B601CTAH0 |  |  | 2 |  |  | G |  |  |  |  |  |  |  |
| Multi | N |  | N | 24 | 24 | 71020NS00-967-G |  | OSC,25MHz,+/-25ppm,3.3V,15pF,G,SMD | SaRonix-eCERA Corporation | FK2500025 | EVT | 1 |  | 3 | 2 | G | OSC1,OSC2 |  |  |  |  |  |  |
|  |  |  |  |  | 24 | 710209J00-100-G |  | OSC,25MHz,+/-25ppm,3.3V,15pF,G,SMD | TXC CORPORATION | 7X25000008 |  |  | 2 |  |  | G |  |  |  |  |  |  |  |
| Single | ND |  | Y(3) | 25 | 25 | 62120HT00-024-G |  | ECAP,SPEA,100uF,+/-20%,10V,105C,G,SMD2816,ESR<=40mOhm | PANASONIC INDUSTRIAL CO.,LTD. | EEFCX1A101R | EVT | 1 | 2 | 3 | 3 | G | PSTCE3003,PFTCE3003,PETCE3003 |  |  |  |  |  |  |
| Multi | N |  | Y(1) | 26 | 26 | 62012PT00-015-G |  | CAP,22uF,+/-20%,X6S,16V,G,SMD0805 | MURATA ELEC. NORTH AMERICA | GRM21BC81C226M | EVT | 1 | 2 | 3 | 14 | G | PSTC2,PFTC2,PETC2,PSTC3,PFTC3,PETC3,PSRC7,PSRC8,PSRC11,PSRC12,PSRC15,PSTC3000,PFTC3000,PETC3000 |  |  |  |  |  |  |
|  |  |  |  |  | 26 | 62012PT00-023-G |  | CAP,22uF,+/-20%,X6S,16V,G,SMD0805 | TAIYO ELECTRIC IND.CO.LTD | EDK212BC6226MG-T |  | 1 | 2 | 3 |  | G |  |  |  |  |  |  |  |
| Multi | Y | 2 | Y(3) | 27 | 27 | 620108000-015-G | - | CAP,100pF,+/-5%,NPO(C0G),50V,G,SMD0402 | MURATA ELEC. NORTH AMERICA | GRM1555C1H101J | EVT | 1 | 2 | 3 | 3 | G | PSTC4,PFTC4,PETC4 |  |  |  |  |  |  |
|  |  |  |  |  | 27 | 62010800A-012-G |  | CAP,100pF,+/-5%,NPO(C0G),50V,G,SMD0402 | WALSIN TECHNOLOGY CORPORATION | 0402N101J500CT |  | 1 | 2 | 3 |  | G |  |  |  |  |  |  |  |
|  |  |  |  |  | 27 | 620108000-026-G |  | CAP,100pF,+/-5%,NPO(C0G),50V,G,SMD0402 | SAMSUNG SEMICONDUCTOR | CL05C101JB5NNNC |  | 1 | 2 | 3 |  | G |  |  |  |  |  |  |  |
|  |  |  |  |  | 27 | 620108000-023-G |  | CAP,100pF,+/-5%,NPO(C0G),50V,G,SMD0402 | TAIYO ELECTRIC IND.CO.LTD | UMK105CG101JV-F |  | 1 | 2 | 3 |  | G |  |  |  |  |  |  |  |
| Multi | ND | ND | Y(1) | 28 | 28 | 62010L800-015-G | - | CAP,1nF,+/-5%,NPO(C0G),50V,G,SMD0402 | MURATA ELEC. NORTH AMERICA | GRM1555C1H102J | EVT | 1 | 2 | 3 | 3 | G | PSTC5,PFTC5,PETC5 |  |  |  |  |  |  |
|  |  |  |  |  | 28 | 62010L800-012-G |  | CAP,1nF,+/-5%,NPO(C0G),50V,G,SMD0402 | WALSIN TECHNOLOGY CORPORATION | 0402N102J500CT |  | 1 | 2 | 3 |  | G |  |  |  |  |  |  |  |
|  |  |  |  |  | 28 | 62010L800-026-G |  | CAP,1nF,+/-5%,NPO(C0G),50V,G,SMD0402 | SAMSUNG SEMICONDUCTOR | CL05C102JB5NNNC |  | 1 | 2 | 3 |  | G |  |  |  |  |  |  |  |
| Single | ND |  | Y(1) | 29 | 29 | 62012T500-015-G |  | CAP,22uF,+/-20%,X7S,25V,G,SMD1206 | MURATA ELEC. NORTH AMERICA | GRM31CC71E226ME11L | EVT | 1 | 2 | 3 | 41 | G | PSRC2,PSTC6,PFTC6,PETC6,PSTC7,PFTC7,PETC7,PSTC8,PFTC8,PETC8,PSTC9,PFTC9,PETC9,PSRC17,PSTC3005,PFTC3005,PETC3005,PSTC3006,PFTC3006,PETC3006,PSTC3007,PFTC3007,PETC3007,PSTC3010,PFTC3010,PETC3010,PSTC3011,PFTC3011,PETC3011,PSTC3012,PFTC3012,PETC3012,PSTC3013,PFTC3013,PETC3013,PFTC3014,PETC3014,PFTC3015,PETC3015,PFTC3016,PETC3016 |  |  |  |  |  |  |
| Multi | Y | 2 | Y(3) | 30 | 30 | 620103U00-015-G | - | CAP,470pF,+/-10%,X7R,50V,G,SMD0402 | MURATA ELEC. NORTH AMERICA | GRM155R71H471K | EVT | 1 | 2 | 3 | 3 | G | PSTC10,PFTC10,PETC10 |  |  |  |  |  |  |
|  |  |  |  |  | 30 | 620103U00-012-G |  | CAP,470pF,+/-10%,X7R,50V,G,SMD0402 | WALSIN TECHNOLOGY CORPORATION | 0402B471K500CT |  | 1 | 2 | 3 |  | G |  |  |  |  |  |  |  |
|  |  |  |  |  | 30 | 620103U00-026-G |  | CAP,470pF,+/-10%,X7R,50V,G,SMD0402 | SAMSUNG SEMICONDUCTOR | CL05B471KB5NNNC |  | 1 | 2 | 3 |  | G |  |  |  |  |  |  |  |
|  |  |  |  |  | 30 | 620103U00-023-G |  | CAP,470pF,+/-10%,X7R,50V,G,SMD0402 | TAIYO ELECTRIC IND.CO.LTD | UMK105B7471KV-F |  | 1 | 2 | 3 |  | G |  |  |  |  |  |  |  |
| Multi | Y | 2 | Y(3) | 31 | 31 | 62010FG00-015-G | - | CAP,3.3pF,+/-0.25pF,NPO(C0G),50V,G,SMD0402 | MURATA ELEC. NORTH AMERICA | GRM1555C1H3R3C | EVT | 1 | 2 | 3 | 3 | G | PSTC11,PFTC11,PETC11 |  |  |  |  |  |  |
|  |  |  |  |  | 31 | 62010FG08-012-G |  | CAP,3.3pF,+/-0.25pF,NPO(C0G),50V,G,SMD0402 | WALSIN TECHNOLOGY CORPORATION | 0402N3R3C500CT |  | 1 | 2 | 3 |  | G |  |  |  |  |  |  |  |
|  |  |  |  |  | 31 | 62010FG00-026-G |  | CAP,3.3pF,+/-0.25pF,NPO(C0G),50V,G,SMD0402 | SAMSUNG SEMICONDUCTOR | CL05C3R3CB5ANNC |  | 1 | 2 | 3 |  | G |  |  |  |  |  |  |  |
| Multi | Y | 2 | Y(3) | 32 | 32 | 620107L00-015-G | - | CAP,2.2nF,+/-10%,X7R,50V,G,SMD0402 | MURATA ELEC. NORTH AMERICA | GRM155R71H222K | EVT | 1 | 2 | 3 | 3 | G | PSTC12,PFTC12,PETC12 |  |  |  |  |  |  |
|  |  |  |  |  | 32 | 620107L00-012-G |  | CAP,2.2nF,+/-10%,X7R,50V,G,SMD0402 | WALSIN TECHNOLOGY CORPORATION | 0402B222K500CT |  | 1 | 2 | 3 |  | G |  |  |  |  |  |  |  |
|  |  |  |  |  | 32 | 620107L00-026-G |  | CAP,2.2nF,+/-10%,X7R,50V,G,SMD0402 | SAMSUNG SEMICONDUCTOR | CL05B222KB5NNNC |  | 1 | 2 | 3 |  | G |  |  |  |  |  |  |  |
|  |  |  |  |  | 32 | 620107L03-023-G |  | CAP,2.2nF,+/-10%,X7R,50V,G,SMD0402 | TAIYO ELECTRIC IND.CO.LTD | UMK105B7222KV-F |  | 1 | 2 | 3 |  | G |  |  |  |  |  |  |  |
| Multi | ND | ND | Y(1) | 33 | 33 | 62012A400-015-G | - | CAP,100nF,+/-10%,X7R,25V,G,SMD0402 | MURATA ELEC. NORTH AMERICA | GRM155R71E104KE14D | EVT | 1 | 2 | 3 | 8 | G | PSRC1,PSRC6,PSTC3002,PFTC3002,PETC3002,PSTC3008,PFTC3008,PETC3008 |  |  |  |  |  |  |
|  |  |  |  |  | 33 | 62012A400-023-G |  | CAP,100nF,+/-10%,X7R,25V,G,SMD0402 | TAIYO ELECTRIC IND.CO.LTD | TMK105B7104KV-FR |  | 1 | 2 | 3 |  | G |  |  |  |  |  |  |  |
|  |  |  |  |  | 33 | 62012A400-026-G |  | CAP,100nF,+/-10%,X7R,25V,G,SMD0402 | SAMSUNG SEMICONDUCTOR | CL05B104KA5NNNC |  | 1 | 2 | 3 |  | G |  |  |  |  |  |  |  |
|  |  |  |  |  | 33 | 62012A400-012-G |  | CAP,100nF,+/-10%,X7R,25V,G,SMD0402 | WALSIN TECHNOLOGY CORPORATION | 0402B104K250CT |  | 1 | 2 | 3 |  | G |  |  |  |  |  |  |  |
| Multi | N |  | Y(1) | 34 | 34 | 62012T300-015-G |  | CAP,1uF,+/-10%,X7S,25V,G,SMD0402 | MURATA ELEC. NORTH AMERICA | GRM155C71E105KE11D | EVT | 1 | 2 | 3 | 4 | G | PSRC4,PSTC3003,PFTC3003,PETC3003 |  |  |  |  |  |  |
|  |  |  |  |  | 34 | 620138700-026-G |  | CAP,1uF,+/-10%,X6S,25V,G,SMD0402 | SAMSUNG SEMICONDUCTOR | CL05X105KA5NQNC |  | 1 | 2 | 3 |  | G |  |  |  |  |  |  |  |
|  |  |  |  |  | 34 | 620138700-015-G |  | CAP,1uF,+/-10%,X6S,25V,G,SMD0402 | MURATA | GRM155C81E105KE11D |  | 1 | 2 | 3 |  | G |  |  |  |  |  |  |  |
| Multi | N |  | Y(3) | 35 | 35 | 62012GG00-015-G |  | CAP,10uF,+/-10%,X7S,25V,G,SMD0805 | MURATA ELEC. NORTH AMERICA | GRM21BC71E106K | EVT | 1 | 2 | 3 | 7 | G | PSRC3,PSTC3004,PFTC3004,PETC3004,PSTC3009,PFTC3009,PETC3009 |  |  |  |  |  |  |
|  |  |  |  |  | 35 | 62012GG00-012-G |  | CAP,10uF,+/-10%,X7S,25V,G,SMD0805 | WALSIN TECHNOLOGY CORPORATION | 0805A106K250CT |  | 1 | 2 | 3 |  | G |  |  |  |  |  |  |  |
| Multi | ND |  | N | 36 | 36 | 630335M00-088-G |  | IND,820nH@100KHz,+/-20%,13A,8mOhm,SHLD,G,SMD | COOPER BUSSMANN, INC. | HCM0703-R82-R | EVT | 1 |  |  | 3 | G | PSTL1,PFTL1,PETL1 |  |  |  |  |  |  |
|  |  |  |  |  | 36 | 63035Y800-051-G |  | Coil Ind,Shielded(SHLD),820nH@100KHz,+/-20%,13A,8mOhm,SMD,7.6*6.9*3.0,,,G | PULSE ELECTRONICS (SINGAPORE) | PA4341.821NLT |  |  | 2 |  |  | G |  |  |  |  |  |  |  |
|  |  |  |  |  | 36 | 63032RP05-129-G |  | IND,820nH@100KHz,+/-20%,13A,8mOhm,SHLD,G,SMD | MAG.LAYERS, SCIENTIFIC-TECHNICS (KUNSHAN) CO., LTD. | SPS-06CZ-R82M-V1 |  |  |  | 3 |  | G |  |  |  |  |  |  |  |
| Multi | ND |  | N | 37 | 37 | 630341400-088-G |  | IND,22nH@1MHz,+/-20%,19A,368uOhm,SHLD,G,SMD | COOPER BUSSMANN, INC. | FP0404R1-R022-R | EVT | 1 |  | 3 | 3 | G | PSTL2,PFTL2,PETL2 |  |  |  |  |  |  |
|  |  |  |  |  | 37 | 630362G00-065-G |  | 22nH@100KHz,+/-20%,19A,0.32mOhm,SHLD,G,SMD | Delta | HCB0430-220 |  |  | 2 |  |  | G |  |  |  |  |  |  |  |
| Multi | ND | ND | Y(4) | 38 | 38 | 61010LA00-017-G | - | RES,4.7KOhm,+/-1%,1/16W,G,SMD0402 | KOA SPEER ELECTRONICS, INC. | RK73H1ETTP4701F | EVT | 1 | 2 | 3 | 45 | G | PSTR1,PFTR1,PETR1,R336,R1605,R1700,R1701,R1702,R1703,R1704,R1705,R1706,R1707,R1708,R1709,R1710,R1711,R1712,R1713,R1714,R1715,R1716,R1717,R1718,R1719,R1720,R1721,R1722,R1723,R1724,R1725,R1726,R1727,R1728,R1729,R1730,R1731,R1732,R1733,R1734,R1735,R1736,R1737,R1738,R1739 |  |  |  |  |  |  |
|  |  |  |  |  | 38 | 61010LA00-012-G |  | RES,4.7KOhm,+/-1%,1/16W,G,SMD0402 | WALSIN TECHNOLOGY CORPORATION | WR04X4701FTL |  | 1 | 2 | 3 |  | G |  |  |  |  |  |  |  |
|  |  |  |  |  | 38 | 61010LA00-011-G |  | RES,4.7KOhm,+/-1%,1/16W,G,SMD0402 | YAGEO CORPORATION COMPONENT | RC0402FR-074K7L |  | 1 | 2 | 3 |  | G |  |  |  |  |  |  |  |
|  |  |  |  |  | 38 | 61010LA00-044-G |  | RES,4.7KOhm,+/-1%,1/16W,G,SMD0402 | TA-I TECHNOLOGY CO., LTD | RM04FTN4701 |  | 1 | 2 | 3 |  | G |  |  |  |  |  |  |  |
| Multi | N | ND | Y(4) | 39 | 39 | 610107A00-017-G | - | RES,0 Ohm,+/-5%,1/16W,G,SMD0402 | KOA SPEER ELECTRONICS, INC. | RK73Z1ETTP | EVT | 1 | 2 | 3 | 146 | G | PSTR2,PFTR2,PETR2,R5,PSTR7,PFTR7,PETR7,R8,PSTR8,PSRR8,PFTR8,PETR8,PSRR9,R10,PSTR14,PFTR14,PETR14,PSRR15,PSRR18,PSTR22,PSRR22,PFTR22,PETR22,R60,R65,R511,R568,R569,R570,R571,R1888,R1889,R1890,R1891,R1892,R1893,R1894,R1895,R1896,R1897,R1898,R1899,R1900,R1901,R1902,R1903,R1988,R1989,R1990,R1991,R1992,R1993,R1994,R1995,R1996,R1997,R1998,R1999,R2000,R2001,R2002,R2003,R2004,R2005,R2006,R2007,R2008,R2009,R2010,R2011,R2012,R2013,R2014,R2015,R2016,R2017,R2018,R2019,R2020,R2021,R2022,R2023,R2024,R2025,R2026,R2027,R2028,R2029,R2030,R2031,R2032,R2033,R2034,R2035,R2036,R2037,R2038,R2039,R2040,R2041,R2042,R2043,R2044,R2045,R2046,R2047,R2061,R2066,R2067,R2070,R2085,R2086,R2152,R2153,R2154,R2155,R2158,R2180,R2181,R2182,R2183,R2184,R2185,R2186,R2187,R2188,R2189,R2190,R2191,R2192,R2193,R2194,R2195,R2196,R2197,R2198,R2199,PSTR3001,PFTR3001,PETR3001,PSTR3002,PFTR3002,PETR3002,PSTR3003,PFTR3003,PETR3003 |  |  |  |  |  |  |
|  |  |  |  |  | 39 | 610107A00-012-G |  | RES,0 Ohm,+/-5%,1/16W,G,SMD0402 | WALSIN TECHNOLOGY CORPORATION | WR04X000PTL |  | 1 | 2 | 3 |  | G |  |  |  |  |  |  |  |
|  |  |  |  |  | 39 | 610107A00-011-G |  | RES,0 Ohm,+/-5%,1/16W,G,SMD0402 | YAGEO CORPORATION COMPONENT | RC0402JR-070RL | EVT | 1 | 2 | 3 |  | G |  |  |  |  |  |  |  |
|  |  |  |  |  | 39 | 610107A00-044-G |  | RES,0 Ohm,+/-5%,1/16W,G,SMD0402 | TA-I TECHNOLOGY CO., LTD | RM04JTN0 |  | 1 | 2 | 3 |  | G |  |  |  |  |  |  |  |
|  |  |  |  |  | 39 | 610107A00-024-G |  | RES,0 Ohm,+/-5%,1/16W,G,SMD0402 | PANASONIC INDUSTRIAL CO.,LTD. | ERJ2GE0R00X |  | 1 | 2 | 3 |  | G |  |  |  |  |  |  |  |
|  |  |  |  |  | 39 | 610107A00-029-G |  | RES,0 Ohm,+/-5%,1/16W,G,SMD0402 | VISHAY ENTER TECHNO LOGY.INC | CRCW04020000Z0ED |  | 1 | 2 | 3 |  | G |  |  |  |  |  |  |  |
| Multi | ND | ND | Y(4) | 40 | 40 | 61011HA00-017-G |  | RES,1 Ohm,+/-1%,1/16W,G,SMD0402 | KOA SPEER ELECTRONICS, INC. | RK73H1ETTP1R00F |  | 1 | 2 | 3 | 4 | G | PSTR4,PFTR4,PETR4,PSRR5 |  |  |  |  |  |  |
|  |  |  |  |  | 40 | 61011HA00-012-G |  | RES,1 Ohm,+/-1%,1/16W,G,SMD0402 | WALSIN TECHNOLOGY CORPORATION | WR04W1R00FTL | EVT | 1 | 2 | 3 |  | G |  |  |  |  |  |  |  |
|  |  |  |  |  | 40 | 61011HA00-011-G |  | RES,1 Ohm,+/-1%,1/16W,G,SMD0402 | YAGEO CORPORATION COMPONENT | RC0402FR-071RL |  | 1 | 2 | 3 |  | G |  |  |  |  |  |  |  |
|  |  |  |  |  | 40 | 61011HA00-044-G |  | RES,1 Ohm,+/-1%,1/16W,G,SMD0402 | TA-I TECHNOLOGY CO., LTD | RM04FTN1R00 |  | 1 | 2 | 3 |  | G |  |  |  |  |  |  |  |
|  |  |  |  |  | 40 | 61011HA00-029-G |  | RES,1 Ohm,+/-1%,1/16W,G,SMD0402 | VISHAY ENTER TECHNO LOGY.INC | CRCW04021R00FNED |  | 1 | 2 | 3 |  | G |  |  |  |  |  |  |  |
| Multi | N |  | Y(5) | 41 | 41 | 61100QD00-017-G |  | RES,787 Ohm,+/-0.1%,1/16W,G,SMD0402 | KOA SPEER ELECTRONICS, INC. | RN731ETTP7870B25 | EVT | 1 |  |  | 3 | G | PSTR5,PFTR5,PETR5 |  |  |  |  |  |  |
|  |  |  |  |  | 41 | 61100QD00-011-G |  | RES,787 Ohm,+/-0.1%,1/16W,G,SMD0402 | YAGEO CORPORATION COMPONENT | RT0402BRD07787RL |  |  | 2 |  |  | G |  |  |  |  |  |  |  |
|  |  |  |  |  | 41 | 61100QD00-044-G |  | RES,787 Ohm,+/-0.1%,1/16W,G,SMD0402 | TA-I TECHNOLOGY CO., LTD | RB04BTP7870 |  |  |  | 3 |  | G |  |  |  |  |  |  |  |
|  |  |  |  |  | 41 | 61100QD00-012-G |  | RES,787 Ohm,+/-0.1%,1/16W,G,SMD0402 | WALSIN TECHNOLOGY CORPORATION | WF04U7870BTL |  |  |  |  |  | G |  |  |  |  |  |  |  |
| Multi | ND |  | Y(5) | 42 | 42 | 61100SU00-017-G |  | RES,105 Ohm,+/-0.1%,1/16W,G,SMD0402 | KOA SPEER ELECTRONICS, INC. | RN731ETTP1050B25 | EVT | 1 |  |  | 3 | G | PSTR6,PFTR6,PETR6 |  |  |  |  |  |  |
|  |  |  |  |  | 42 | 61100SU00-011-G |  | RES,105 Ohm,+/-0.1%,1/16W,G,SMD0402 | YAGEO CORPORATION COMPONENT | RT0402BRD07105RL |  |  | 2 |  |  | G |  |  |  |  |  |  |  |
|  |  |  |  |  | 42 | 61100SU00-044-G |  | RES,105 Ohm,+/-0.1%,1/16W,G,SMD0402 | TA-I TECHNOLOGY CO., LTD | RB04BTP1050 |  |  |  | 3 |  | G |  |  |  |  |  |  |  |
|  |  |  |  |  | 42 | 61100SU00-012-G |  | RES,105 Ohm,+/-0.1%,1/16W,G,SMD0402 | WALSIN TECHNOLOGY CORPORATION | WF04U1050BTL |  |  |  |  |  | G |  |  |  |  |  |  |  |
| Multi | ND | ND | Y(4) | 43 | 43 | 61011BD00-017-G |  | RES,46.4KOhm,+/-1%,1/16W,G,SMD0402 | KOA SPEER ELECTRONICS, INC. | RK73H1ETTP4642F | EVT | 1 | 2 | 3 | 3 | G | PSTR9,PFTR9,PETR9 |  |  |  |  |  |  |
|  |  |  |  |  | 43 | 61011BD00-011-G |  | RES,46.4KOhm,+/-1%,1/16W,G,SMD0402 | YAGEO CORPORATION COMPONENT | RC0402FR-0746K4L |  | 1 | 2 | 3 |  | G |  |  |  |  |  |  |  |
|  |  |  |  |  | 43 | 61011BD00-012-G |  | RES,46.4KOhm,+/-1%,1/16W,G,SMD0402 | WALSIN TECHNOLOGY CORPORATION | WR04X4642FTL |  | 1 | 2 | 3 |  | G |  |  |  |  |  |  |  |
|  |  |  |  |  | 43 | 61011BD00-044-G |  | RES,46.4KOhm,+/-1%,1/16W,G,SMD0402 | TA-I TECHNOLOGY CO., LTD | RM04FTN4642 |  | 1 | 2 | 3 |  | G |  |  |  |  |  |  |  |
| Multi | ND | ND | Y(4) | 44 | 44 | 610124U00-017-G | - | RES,7.87KOhm,+/-1%,1/16W,G,SMD0402 | KOA SPEER ELECTRONICS, INC. | RK73H1ETTP7871F | EVT | 1 | 2 | 3 | 3 | G | PSTR10,PFTR10,PETR10 |  |  |  |  |  |  |
|  |  |  |  |  | 44 | 610124U00-012-G |  | RES,7.87KOhm,+/-1%,1/16W,G,SMD0402 | WALSIN TECHNOLOGY CORPORATION | WR04X7871FTL |  | 1 | 2 | 3 |  | G |  |  |  |  |  |  |  |
|  |  |  |  |  | 44 | 610124U00-011-G |  | RES,7.87KOhm,+/-1%,1/16W,G,SMD0402 | YAGEO CORPORATION COMPONENT | RC0402FR-077K87L |  | 1 | 2 | 3 |  | G |  |  |  |  |  |  |  |
|  |  |  |  |  | 44 | 610124U00-044-G |  | RES,7.87KOhm,+/-1%,1/16W,G,SMD0402 | TA-I TECHNOLOGY CO., LTD | RM04FTN7871 |  | 1 | 2 | 3 |  | G |  |  |  |  |  |  |  |
| Multi | N | ND | Y(4) | 45 | 45 | 610112J00-017-G | - | RES,200 Ohm,+/-1%,1/16W,G,SMD0402 | KOA SPEER ELECTRONICS, INC. | RK73H1ETTP2000F |  | 1 | 2 | 3 | 3 | G | PSTR11,PFTR11,PETR11 |  |  |  |  |  |  |
|  |  |  |  |  | 45 | 610112J00-012-G |  | RES,200 Ohm,+/-1%,1/16W,G,SMD0402 | WALSIN TECHNOLOGY CORPORATION | WR04X2000FTL |  | 1 | 2 | 3 |  | G |  |  |  |  |  |  |  |
|  |  |  |  |  | 45 | 610112J00-011-G |  | RES,200 Ohm,+/-1%,1/16W,G,SMD0402 | YAGEO CORPORATION COMPONENT | RC0402FR-07200RL | EVT | 1 | 2 | 3 |  | G |  |  |  |  |  |  |  |
|  |  |  |  |  | 45 | 610112J00-044-G |  | RES,200 Ohm,+/-1%,1/16W,G,SMD0402 | TA-I TECHNOLOGY CO., LTD | RM04FTN2000 |  | 1 | 2 | 3 |  | G |  |  |  |  |  |  |  |
|  |  |  |  |  | 45 | 610112J00-029-G |  | RES,200 Ohm,+/-1%,1/16W,G,SMD0402 | VISHAY ENTER TECHNO LOGY.INC | CRCW0402200RFKED |  | 1 | 2 | 3 |  | G |  |  |  |  |  |  |  |
|  |  |  |  |  | 45 | 610112J00-024-G |  | RES,200 Ohm,+/-1%,1/16W,G,SMD0402 | PANASONIC INDUSTRIAL CO.,LTD. | ERJ2RKF2000X |  | 1 | 2 | 3 |  | G |  |  |  |  |  |  |  |
| Multi | N | Other | Y(4) | 46 | 46 | 61011JY00-017-G | - | RES,39.2KOhm,+/-1%,1/16W,G,SMD0402 | KOA SPEER ELECTRONICS, INC. | RK73H1ETTP3922F |  | 1 | 2 | 3 | 3 | G | PSTR15,PFTR15,PETR15 |  |  |  |  |  |  |
|  |  |  |  |  | 46 | 61011JY00-012-G |  | RES,39.2KOhm,+/-1%,1/16W,G,SMD0402 | WALSIN TECHNOLOGY CORPORATION | WR04X3922FTL |  | 1 | 2 | 3 |  | G |  |  |  |  |  |  |  |
|  |  |  |  |  | 46 | 61011JY00-011-G |  | RES,39.2KOhm,+/-1%,1/16W,G,SMD0402 | YAGEO CORPORATION COMPONENT | RC0402FR-0739K2L |  | 1 | 2 | 3 |  | G |  |  |  |  |  |  |  |
|  |  |  |  |  | 46 | 61011JY00-044-G |  | RES,39.2KOhm,+/-1%,1/16W,G,SMD0402 | TA-I TECHNOLOGY CO., LTD | RM04FTN3922 | EVT | 1 | 2 | 3 |  | G |  |  |  |  |  |  |  |
|  |  |  |  |  | 46 | 61011JY00-029-G |  | RES,39.2KOhm,+/-1%,1/16W,G,SMD0402 | VISHAY ENTER TECHNO LOGY.INC | CRCW040239K2FKED |  | 1 | 2 | 3 |  | G |  |  |  |  |  |  |  |
| Single | ND |  | N | 47 | 47 | 32013P700-238-G |  | IC,Regulator,IR3448MTRPBF,ADJ,16A,G,PQFN-33,SMD | INTERNATIONAL RECTIFIER | IR3448MTRPBF | EVT | 1 | 2 | 3 | 3 | G | PSTU1,PFTU1,PETU1 |  |  |  |  |  |  |
| Multi | ND |  | Y(3) | 48 | 48 | 62012P100-015-G |  | CAP,2.2uF,+/-20%,X7S,10V,G,SMD0402 | MURATA ELEC. NORTH AMERICA | GRM155C71A225M | EVT | 1 | 2 | 3 | 1 | G | PSRC5 |  |  |  |  |  |  |
|  |  |  |  |  | 48 | 62012P100-012-G |  | CAP,2.2uF,+/-20%,X7S,10V,G,SMD0402 | WALSIN TECHNOLOGY CORPORATION | 0402A225M100CT |  | 1 | 2 | 3 |  | G |  |  |  |  |  |  |  |
| Multi | Y | 2 | Y(3) | 49 | 49 | 620105U00-015-G | - | CAP,220pF,+/-10%,X7R,50V,G,SMD0402 | MURATA ELEC. NORTH AMERICA | GRM155R71H221K |  | 1 | 2 | 3 | 1 | G | PSRC14 |  |  |  |  |  |  |
|  |  |  |  |  | 49 | 620105U00-012-G |  | CAP,220pF,+/-10%,X7R,50V,G,SMD0402 | WALSIN TECHNOLOGY CORPORATION | 0402B221K500CT |  | 1 | 2 | 3 |  | G |  |  |  |  |  |  |  |
|  |  |  |  |  | 49 | 620105U00-026-G |  | CAP,220pF,+/-10%,X7R,50V,G,SMD0402 | SAMSUNG SEMICONDUCTOR | CL05B221KB5NNNC | EVT | 1 | 2 | 3 |  | G |  |  |  |  |  |  |  |
| Multi | N |  | Y(3) | 50 | 50 | 62012H100-015-G |  | CAP,10uF,+/-20%,X6S,10V,G,SMD0603 | MURATA ELEC. NORTH AMERICA | GRM188C81A106M | EVT | 1 | 2 | 3 | 1 | G | PSRC16 |  |  |  |  |  |  |
|  |  |  |  |  | 50 | 62012H100-023-G |  | CAP,10uF,+/-20%,X6S,10V,G,SMD0603 | TAIYO ELECTRIC IND.CO.LTD | LMK107BC6106MA-T |  | 1 | 2 | 3 |  | G |  |  |  |  |  |  |  |
|  |  |  |  |  | 50 | 62012H100-026-G |  | CAP,10uF,+/-20%,X6S,10V,G,SMD0603 | SAMSUNG SEMICONDUCTOR | CL10X106MP8NRNC |  | 1 | 2 | 3 |  | G |  |  |  |  |  |  |  |
| Multi | N |  | N | 51 | 51 | 72010RE00-015-G |  | FB,26 Ohm@100MHz,+/-25%,6A,7mOhm,G,SMD0603 | MURATA ELEC. NORTH AMERICA | BLM18KG260TN1D | EVT | 1 |  | 3 | 1 | G | PSRL1 |  |  |  |  |  |  |
|  |  |  |  |  | 51 | 72010SJ00-059-G |  | FB,Multilayer,10mOhm,26Ohm@100MHz,+/-25%,6A,,SMD0603,G | TAI-TECH ADVANCED ELECTRONICS CO., LTD. | HCB1608KF-260T60 |  |  | 2 |  |  | G |  |  |  |  |  |  |  |
| Multi | N |  | N | 52 | 52 | 63032PP00-088-G |  | IND,4.7uH@100KHz,+/-20%,5.5A,40mOhm,SHLD,G,SMD | COOPER BUSSMANN, INC. | HCM0703-4R7-R | EVT | 1 |  |  | 1 | G | PSRL2 |  |  |  |  |  |  |
|  |  |  |  |  | 52 | 63030PW00-034-G |  | Coil Ind,Shielded(SHLD),4.7uH@100KHz,+/-20%,5.5A,40mOhm,SMD,7.3*6.6*3.0,G | CYNTEC CO. LTD | PCMC063T-4R7MN |  |  | 2 |  |  | G |  |  |  |  |  |  |  |
|  |  |  |  |  | 52 | 63031AD04-129-G |  | IND,4.7uH@100KHz,+/-20%,5.5A,40mOhm,SHLD,G,SMD | MAG.LAYERS, SCIENTIFIC-TECHNICS (KUNSHAN) CO., LTD. | SPS-06CZ-4R7M-V1 |  |  |  | 3 |  | G |  |  |  |  |  |  |  |
| Multi | ND | ND | Y(4) | 53 | 53 | 610117D00-017-G | - | RES,13.3KOhm,+/-1%,1/16W,G,SMD0402 | KOA SPEER ELECTRONICS, INC. | RK73H1ETTP1332F |  | 1 | 2 | 3 | 1 | G | PSRR1 |  |  |  |  |  |  |
|  |  |  |  |  | 53 | 610117D00-012-G |  | RES,13.3KOhm,+/-1%,1/16W,G,SMD0402 | WALSIN TECHNOLOGY CORPORATION | WR04X1332FTL |  | 1 | 2 | 3 |  | G |  |  |  |  |  |  |  |
|  |  |  |  |  | 53 | 610117D00-011-G |  | RES,13.3KOhm,+/-1%,1/16W,G,SMD0402 | YAGEO CORPORATION COMPONENT | RC0402FR-0713K3L | EVT | 1 | 2 | 3 |  | G |  |  |  |  |  |  |  |
|  |  |  |  |  | 53 | 610117D00-044-G |  | RES,13.3KOhm,+/-1%,1/16W,G,SMD0402 | TA-I TECHNOLOGY CO., LTD | RM04FTN1332 |  | 1 | 2 | 3 |  | G |  |  |  |  |  |  |  |
| Multi | ND | ND | Y(4) | 54 | 54 | 610114S00-017-G | - | RES,4.99KOhm,+/-1%,1/16W,G,SMD0402 | KOA SPEER ELECTRONICS, INC. | RK73H1ETTP4991F |  | 1 | 2 | 3 | 1 | G | PSRR3 |  |  |  |  |  |  |
|  |  |  |  |  | 54 | 610114S00-012-G |  | RES,4.99KOhm,+/-1%,1/16W,G,SMD0402 | WALSIN TECHNOLOGY CORPORATION | WR04X4991FTL | EVT | 1 | 2 | 3 |  | G |  |  |  |  |  |  |  |
|  |  |  |  |  | 54 | 610114S00-011-G |  | RES,4.99KOhm,+/-1%,1/16W,G,SMD0402 | YAGEO CORPORATION COMPONENT | RC0402FR-074K99L |  | 1 | 2 | 3 |  | G |  |  |  |  |  |  |  |
|  |  |  |  |  | 54 | 610114S00-044-G |  | RES,4.99KOhm,+/-1%,1/16W,G,SMD0402 | TA-I TECHNOLOGY CO., LTD | RM04FTN4991 |  | 1 | 2 | 3 |  | G |  |  |  |  |  |  |  |
|  |  |  |  |  | 54 | 610114S00-024-G |  | RES,4.99KOhm,+/-1%,1/16W,G,SMD0402 | PANASONIC INDUSTRIAL CO.,LTD. | ERJ2RKF4991X |  | 1 | 2 | 3 |  | G |  |  |  |  |  |  |  |
| Multi | N | ND | Y(4) | 55 | 55 | 61010G500-017-G | - | RES,10KOhm,+/-1%,1/16W,G,SMD0402 | KOA SPEER ELECTRONICS, INC. | RK73H1ETTP1002F |  | 1 | 2 | 3 | 1 | G | PSRR6 |  |  |  |  |  |  |
|  |  |  |  |  | 55 | 61010G500-012-G |  | RES,10KOhm,+/-1%,1/16W,G,SMD0402 | WALSIN TECHNOLOGY CORPORATION | WR04X1002FTL |  | 1 | 2 | 3 |  | G |  |  |  |  |  |  |  |
|  |  |  |  |  | 55 | 61010G500-011-G |  | RES,10KOhm,+/-1%,1/16W,G,SMD0402 | YAGEO CORPORATION COMPONENT | RC0402FR-0710KL | EVT | 1 | 2 | 3 |  | G |  |  |  |  |  |  |  |
|  |  |  |  |  | 55 | 61010G500-044-G |  | RES,10KOhm,+/-1%,1/16W,G,SMD0402 | TA-I TECHNOLOGY CO., LTD | RM04FTN1002 |  | 1 | 2 | 3 |  | G |  |  |  |  |  |  |  |
|  |  |  |  |  | 55 | 61010G500-029-G |  | RES,10KOhm,+/-1%,1/16W,G,SMD0402 | VISHAY ENTER TECHNO LOGY.INC | CRCW040210K0FKED |  | 1 | 2 | 3 |  | G |  |  |  |  |  |  |  |
|  |  |  |  |  | 55 | 61010G500-024-G |  | RES,10KOhm,+/-1%,1/16W,G,SMD0402 | PANASONIC INDUSTRIAL CO.,LTD. | ERJ2RKF1002X |  | 1 | 2 | 3 |  | G |  |  |  |  |  |  |  |
| Multi | N |  | N | 56 | 56 | 611004M00-017-G |  | RES,16.5KOhm,+/-0.1%,1/16W,G,SMD0402 | KOA SPEER ELECTRONICS, INC. | RN731ETTP1652B25 | EVT | 1 |  | 3 | 1 | G | PSRR17 |  |  |  |  |  |  |
|  |  |  |  |  | 56 | 611004M00-024-G |  | RES,16.5KOhm,+/-0.1%,1/16W,G,SMD0402 | PANASONIC INDUSTRIAL CO.,LTD. | ERA2AEB1652X |  |  | 2 |  |  | G |  |  |  |  |  |  |  |
| Multi | N |  | N | 57 | 57 | 61100YB00-017-G |  | RES,2.94KOhm,+/-0.1%,1/16W,G,SMD0402 | KOA SPEER ELECTRONICS, INC. | RN731ETTP2941B25 | EVT | 1 |  |  | 1 | G | PSRR19 |  |  |  |  |  |  |
|  |  |  |  |  | 57 | 61100YB00-011-G |  | RES,2.94KOhm,+/-0.1%,1/16W,G,SMD0402 | YAGEO CORPORATION COMPONENT | RT0402BRD072K94L |  |  | 2 |  |  | G |  |  |  |  |  |  |  |
|  |  |  |  |  | 57 | 61100YB00-044-G |  | RES,2.94KOhm,+/-0.1%,1/16W,G,SMD0402 | TA-I TECHNOLOGY CO., LTD | RB04BTP2941 |  |  |  | 3 |  | G |  |  |  |  |  |  |  |
| Single | ND |  | ND | 58 | 58 | 32013PD00-238-G |  | IC,Regulator,IR3883MTRPbF,ADJ,3A,G,QFN-16,SMD | INTERNATIONAL RECTIFIER | IR3883MTRPBF | EVT | 1 | 2 | 3 | 1 | G | PSRU1 |  |  |  |  |  |  |
| Multi | ND | ND | N | 59 | 59 | 510504M00-237-G |  | MOS N/N,BSS138DW-7-F,50V,0.2A,3.5ohm@10V,G,SOT363-6,SMD | DIODES INEORPORATION | BSS138DW-7-F | EVT | 1 |  | 3 | 25 | G | QN19,QN20,QN25,QN26,QN27,QN28,QN29,QN30,QN31,QN33,QN34,QN35,QN36,QN37,QN38,QN39,QN40,QN41,QN42,QN43,QN44,QN45,QN46,QN47,QN48 |  |  |  |  |  |  |
|  |  |  |  |  | 59 | 510507900-223-G |  | MOS N/N,NTJD4001NT1G,30V,0.25A,1.5ohm@4V,G,SOT363-6,SMD | ON SEMICONDUCTOR CORP | NTJD4001NT1G |  |  | 2 |  |  | G |  |  |  |  |  |  |  |
| Multi | ND | ND | N | 60 | 60 | 61011H500-017-G | - | RES,22 Ohm,+/-1%,1/16W,G,SMD0402 | KOA SPEER ELECTRONICS, INC. | RK73H1ETTP22R0F |  | 1 | 2 | 3 | 12 | G | R1,R14,R338,R504,R509,R531,R550,R552,R572,R868,R869,R2148 |  |  |  |  |  |  |
|  |  |  |  |  | 60 | 61011H500-012-G |  | RES,22 Ohm,+/-1%,1/16W,G,SMD0402 | WALSIN TECHNOLOGY CORPORATION | WR04X22R0FTL | EVT | 1 | 2 | 3 |  | G |  |  |  |  |  |  |  |
|  |  |  |  |  | 60 | 61011H500-011-G |  | RES,22 Ohm,+/-1%,1/16W,G,SMD0402 | YAGEO CORPORATION COMPONENT | RC0402FR-0722RL |  | 1 | 2 | 3 |  | G |  |  |  |  |  |  |  |
|  |  |  |  |  | 60 | 61011H500-044-G |  | RES,22 Ohm,+/-1%,1/16W,G,SMD0402 | TA-I TECHNOLOGY CO., LTD | RM04FTN22R0 |  | 1 | 2 | 3 |  | G |  |  |  |  |  |  |  |
|  |  |  |  |  | 60 | 61011H500-024-G |  | RES,22 Ohm,+/-1%,1/16W,G,SMD0402 | PANASONIC INDUSTRIAL CO.,LTD. | ERJ2RKF22R0X |  | 1 | 2 | 3 |  | G |  |  |  |  |  |  |  |
| Multi | N | Other | N | 61 | 61 | 61011MQ00-017-G | - | RES,4.75KOhm,+/-1%,1/16W,G,SMD0402 | KOA SPEER ELECTRONICS, INC. | RK73H1ETTP4751F |  | 1 | 2 | 3 | 2 | G | R2,R4 |  |  |  |  |  |  |
|  |  |  |  |  | 61 | 61011MQ00-011-G |  | RES,4.75KOhm,+/-1%,1/16W,G,SMD0402 | YAGEO CORPORATION COMPONENT | RC0402FR-074K75L | EVT | 1 | 2 | 3 |  | G |  |  |  |  |  |  |  |
|  |  |  |  |  | 61 | 61011MQ00-012-G |  | RES,4.75KOhm,+/-1%,1/16W,G,SMD0402 | WALSIN TECHNOLOGY CORPORATION | WR04X4751FTL |  | 1 | 2 | 3 |  | G |  |  |  |  |  |  |  |
|  |  |  |  |  | 61 | 61011MQ00-044-G |  | RES,4.75KOhm,+/-1%,1/16W,G,SMD0402 | TA-I TECHNOLOGY CO., LTD | RM04FTN4751 |  | 1 | 2 | 3 |  | G |  |  |  |  |  |  |  |
| Multi | N | ND | Y(4) | 62 | 62 | 610107B00-017-G | K9576 | RES,4.7KOhm,+/-5%,1/16W,G,SMD0402 | KOA SPEER ELECTRONICS, INC. | RK73B1ETTP472J |  | 1 | 2 | 3 | 134 | G | R6,R7,R9,R16,R17,R18,R62,R228,R312,R323,R324,R331,R333,R337,R411,R413,R417,R427,R429,R433,R443,R445,R448,R460,R461,R465,R475,R477,R480,R492,R493,R497,R503,R505,R506,R507,R510,R512,R513,R514,R516,R527,R528,R541,R546,R547,R548,R549,R553,R555,R556,R557,R559,R560,R617,R619,R622,R634,R635,R639,R649,R651,R654,R666,R667,R671,R681,R683,R686,R698,R699,R703,R713,R715,R718,R730,R731,R735,R745,R747,R750,R762,R763,R767,R777,R779,R782,R794,R795,R799,R809,R811,R814,R826,R827,R831,R841,R843,R846,R858,R859,R863,R866,R1078,R1079,R1603,R1668,R1681,R1684,R1688,R1694,R1697,R1783,R2128,R2129,R2130,R2131,R2132,R2133,R2134,R2135,R2136,R2137,R2138,R2139,R2140,R2141,R2142,R2143,R2144,R2145,R2146,R2147,R2149 |  |  |  |  |  |  |
|  |  |  |  |  | 62 | 610107B00-012-G |  | RES,4.7KOhm,+/-5%,1/16W,G,SMD0402 | WALSIN TECHNOLOGY CORPORATION | WR04X472JTL |  | 1 | 2 | 3 |  | G |  |  |  |  |  |  |  |
|  |  |  |  |  | 62 | 610107B00-011-G |  | RES,4.7KOhm,+/-5%,1/16W,G,SMD0402 | YAGEO CORPORATION COMPONENT | RC0402JR-074K7L | EVT | 1 | 2 | 3 |  | G |  |  |  |  |  |  |  |
|  |  |  |  |  | 62 | 610107B00-044-G |  | RES,4.7KOhm,+/-5%,1/16W,G,SMD0402 | TA-I TECHNOLOGY CO., LTD | RM04JTN472 |  | 1 | 2 | 3 |  | G |  |  |  |  |  |  |  |
|  |  |  |  |  | 62 | 610107B00-024-G |  | RES,4.7KOhm,+/-5%,1/16W,G,SMD0402 | PANASONIC INDUSTRIAL CO.,LTD. | ERJ2GEJ472X |  | 1 | 2 | 3 |  | G |  |  |  |  |  |  |  |
|  |  |  |  |  | 62 | 610107B00-029-G |  | RES,4.7KOhm,+/-5%,1/16W,G,SMD0402 | VISHAY ENTER TECHNO LOGY.INC | CRCW04024K70JNED |  | 1 | 2 | 3 |  | G |  |  |  |  |  |  |  |
| Multi | N | Other | Y(4) | 63 | 63 | 61010JY00-017-G | - | RES,220 Ohm,+/-5%,1/16W,G,SMD0402 | KOA SPEER ELECTRONICS, INC. | RK73B1ETTP221J |  | 1 | 2 | 3 | 10 | G | R12,R15,R1672,R1673,R1679,R1683,R1687,R1698,R1780,R1782 |  |  |  |  |  |  |
|  |  |  |  |  | 63 | 61010JY00-012-G |  | RES,220 Ohm,+/-5%,1/16W,G,SMD0402 | WALSIN TECHNOLOGY CORPORATION | WR04X221JTL |  | 1 | 2 | 3 |  | G |  |  |  |  |  |  |  |
|  |  |  |  |  | 63 | 61010JY00-011-G |  | RES,220 Ohm,+/-5%,1/16W,G,SMD0402 | YAGEO CORPORATION COMPONENT | RC0402JR-07220RL | EVT | 1 | 2 | 3 |  | G |  |  |  |  |  |  |  |
|  |  |  |  |  | 63 | 61010JY00-044-G |  | RES,220 Ohm,+/-5%,1/16W,G,SMD0402 | TA-I TECHNOLOGY CO., LTD | RM04JTN221 |  | 1 | 2 | 3 |  | G |  |  |  |  |  |  |  |
| Multi | N | ND | Y(4) | 64 | 64 | 610101V00-017-G | K9572 | RES,22 Ohm,+/-5%,1/16W,G,SMD0402 | KOA SPEER ELECTRONICS, INC. | RK73B1ETTP220J |  | 1 | 2 | 3 | 40 | G | R106,R1740,R1741,R1742,R1743,R1744,R1745,R1746,R1747,R1748,R1749,R1750,R1751,R1752,R1753,R1754,R1755,R1756,R1757,R1758,R1759,R1760,R1761,R1762,R1763,R1764,R1765,R1766,R1767,R1768,R1769,R1770,R1771,R1772,R1773,R1774,R1775,R1776,R1777,R1778 |  |  |  |  |  |  |
|  |  |  |  |  | 64 | 610101V00-012-G |  | RES,22 Ohm,+/-5%,1/16W,G,SMD0402 | WALSIN TECHNOLOGY CORPORATION | WR04X220JTL |  | 1 | 2 | 3 |  | G |  |  |  |  |  |  |  |
|  |  |  |  |  | 64 | 610101V00-011-G |  | RES,22 Ohm,+/-5%,1/16W,G,SMD0402 | YAGEO CORPORATION COMPONENT | RC0402JR-0722RL | EVT | 1 | 2 | 3 |  | G |  |  |  |  |  |  |  |
|  |  |  |  |  | 64 | 610101V00-044-G |  | RES,22 Ohm,+/-5%,1/16W,G,SMD0402 | TA-I TECHNOLOGY CO., LTD | RM04JTN220 |  | 1 | 2 | 3 |  | G |  |  |  |  |  |  |  |
|  |  |  |  |  | 64 | 610101V00-024-G |  | RES,22 Ohm,+/-5%,1/16W,G,SMD0402 | PANASONIC INDUSTRIAL CO.,LTD. | ERJ2GEJ220X |  | 1 | 2 | 3 |  | G |  |  |  |  |  |  |  |
| Multi | N | ND | Y(4) | 65 | 65 | 610118100-017-G | - | RES,1.4KOhm,+/-1%,1/16W,G,SMD0402 | KOA SPEER ELECTRONICS, INC. | RK73H1ETTP1401F |  | 1 | 2 | 3 | 2 | G | R251,R252 |  |  |  |  |  |  |
|  |  |  |  |  | 65 | 610118100-012-G |  | RES,1.4KOhm,+/-1%,1/16W,G,SMD0402 | WALSIN TECHNOLOGY CORPORATION | WR04X1401FTL |  | 1 | 2 | 3 |  | G |  |  |  |  |  |  |  |
|  |  |  |  |  | 65 | 610118100-011-G |  | RES,1.4KOhm,+/-1%,1/16W,G,SMD0402 | YAGEO CORPORATION COMPONENT | RC0402FR-071K4L |  | 1 | 2 | 3 |  | G |  |  |  |  |  |  |  |
|  |  |  |  |  | 65 | 610118100-044-G |  | RES,1.4KOhm,+/-1%,1/16W,G,SMD0402 | TA-I TECHNOLOGY CO., LTD | RM04FTN1401 |  | 1 | 2 | 3 |  | G |  |  |  |  |  |  |  |
|  |  |  |  |  | 65 | 610118100-024-G |  | RES,1.4KOhm,+/-1%,1/16W,G,SMD0402 | PANASONIC INDUSTRIAL CO.,LTD. | ERJ2RKF1401X |  | 1 | 2 | 3 |  | G |  |  |  |  |  |  |  |
| Multi | N | ND | Y(4) | 66 | 66 | 61010BG00-017-G | RJ328 | RES,100 Ohm,+/-1%,1/10W,G,SMD0603 | KOA SPEER ELECTRONICS, INC. | RK73H1JTTD1000F | EVT | 1 | 2 | 3 | 72 | G | R313,R317,R319,R330,R332,R335,R410,R412,R415,R426,R428,R431,R442,R444,R447,R458,R459,R463,R474,R476,R479,R490,R491,R495,R616,R618,R621,R632,R633,R637,R648,R650,R653,R664,R665,R669,R680,R682,R685,R696,R697,R701,R712,R714,R717,R728,R729,R733,R744,R746,R749,R760,R761,R765,R776,R778,R781,R792,R793,R797,R808,R810,R813,R824,R825,R829,R840,R842,R845,R856,R857,R861 |  |  |  |  |  |  |
|  |  |  |  |  | 66 | 61010BG00-012-G |  | RES,100 Ohm,+/-1%,1/10W,G,SMD0603 | WALSIN TECHNOLOGY CORPORATION | WR06X1000FTL |  | 1 | 2 | 3 |  | G |  |  |  |  |  |  |  |
|  |  |  |  |  | 66 | 61010BG00-011-G |  | RES,100 Ohm,+/-1%,1/10W,G,SMD0603 | YAGEO CORPORATION COMPONENT | RC0603FR-07100RL |  | 1 | 2 | 3 |  | G |  |  |  |  |  |  |  |
| Multi | N | ND | N | 67 | 67 | 61011QA00-017-G | - | RES,24KOhm,+/-5%,1/16W,G,SMD0402 | KOA SPEER ELECTRONICS, INC. | RK73B1ETTP243J | EVT | 1 | 2 | 3 | 24 | G | R314,R327,R407,R423,R439,R454,R471,R486,R613,R628,R645,R660,R677,R692,R709,R724,R741,R756,R773,R788,R805,R820,R837,R852 |  |  |  |  |  |  |
|  |  |  |  |  | 67 | 61011QA00-011-G |  | RES,24KOhm,+/-5%,1/16W,G,SMD0402 | YAGEO CORPORATION COMPONENT | RC0402JR-0724KL |  | 1 | 2 | 3 |  | G |  |  |  |  |  |  |  |
|  |  |  |  |  | 67 | 61011QA00-012-G |  | RES,24KOhm,+/-5%,1/16W,G,SMD0402 | WALSIN TECHNOLOGY CORPORATION | WR04X243JTL |  | 1 | 2 | 3 |  | G |  |  |  |  |  |  |  |
|  |  |  |  |  | 67 | 61011QA00-044-G |  | RES,24KOhm,+/-5%,1/16W,G,SMD0402 | TA-I TECHNOLOGY CO., LTD | RM04JTN243 |  | 1 | 2 | 3 |  | G |  |  |  |  |  |  |  |
| Multi | ND | ND | N | 68 | 68 | 610115Y00-017-G | - | RES,16.2KOhm,+/-1%,1/16W,G,SMD0402 | KOA SPEER ELECTRONICS, INC. | RK73H1ETTP1622F |  | 1 | 2 | 3 | 24 | G | R318,R326,R406,R422,R438,R455,R470,R487,R612,R629,R644,R661,R676,R693,R708,R725,R740,R757,R772,R789,R804,R821,R836,R853 |  |  |  |  |  |  |
|  |  |  |  |  | 68 | 610115Y00-011-G |  | RES,16.2KOhm,+/-1%,1/16W,G,SMD0402 | YAGEO CORPORATION COMPONENT | RC0402FR-0716K2L | EVT | 1 | 2 | 3 |  | G |  |  |  |  |  |  |  |
|  |  |  |  |  | 68 | 610115Y00-012-G |  | RES,16.2KOhm,+/-1%,1/16W,G,SMD0402 | WALSIN TECHNOLOGY CORPORATION | WR04X1622FTL |  | 1 | 2 | 3 |  | G |  |  |  |  |  |  |  |
|  |  |  |  |  | 68 | 610115Y00-044-G |  | RES,16.2KOhm,+/-1%,1/16W,G,SMD0402 | TA-I TECHNOLOGY CO., LTD | RM04FTN1622 |  | 1 | 2 | 3 |  | G |  |  |  |  |  |  |  |
|  |  |  |  |  | 68 | 610115Y00-024-G |  | RES,16.2KOhm,+/-1%,1/16W,G,SMD0402 | PANASONIC INDUSTRIAL CO.,LTD. | ERJ2RKF1622X |  | 1 | 2 | 3 |  | G |  |  |  |  |  |  |  |
|  |  |  |  |  | 68 | 610115Y00-029-G |  | RES,16.2KOhm,+/-1%,1/16W,G,SMD0402 | VISHAY ENTER TECHNO LOGY.INC | CRCW040216K2FKED |  | 1 | 2 | 3 |  | G |  |  |  |  |  |  |  |
| Multi | N |  | N | 69 | 69 | 61100LQ00-017-G |  | RES,20KOhm,+/-1%,1/16W,G,SMD0402 | KOA SPEER ELECTRONICS, INC. | RN731ETTP2002F50 |  | 1 | 2 | 3 | 44 | G | R348,R1522,R1523,R1524,R1525,R1526,R1527,R1528,R1529,R1530,R1531,R1532,R1533,R1534,R1535,R1536,R1537,R1538,R1539,R1540,R1541,R1542,R1543,R1544,R1545,R1546,R1547,R1548,R1549,R1550,R1551,R1552,R1553,R1554,R1555,R1556,R1557,R1558,R1559,R1560,R1561,R1563,R1565,R1567 |  |  |  |  |  |  |
|  |  |  |  |  | 69 | 61100LQ00-011-G |  | RES,20KOhm,+/-1%,1/16W,G,SMD0402 | YAGEO CORPORATION COMPONENT | RT0402FRE0720KL | EVT | 1 | 2 | 3 |  | G |  |  |  |  |  |  |  |
|  |  |  |  |  | 69 | 61100LQ00-044-G |  | RES,20KOhm,+/-1%,1/16W,G,SMD0402 | TA-I TECHNOLOGY CO., LTD | RB04FTS2002 |  | 1 | 2 | 3 |  | G |  |  |  |  |  |  |  |
|  |  |  |  |  | 69 | 61100LQ00-012-G |  | RES,20KOhm,+/-1%,1/16W,G,SMD0402 | WALSIN TECHNOLOGY CORPORATION | WF04T2002FTL |  | 1 | 2 | 3 |  | G |  |  |  |  |  |  |  |
| Multi | N | ND | N | 70 | 70 | 610114J00-017-G | - | RES,2KOhm,+/-1%,1/16W,G,SMD0402 | KOA SPEER ELECTRONICS, INC. | RK73H1ETTP2001F |  | 1 | 2 | 3 | 5 | G | R501,R502,R508,R544,R545 |  |  |  |  |  |  |
|  |  |  |  |  | 70 | 610114J00-012-G |  | RES,2KOhm,+/-1%,1/16W,G,SMD0402 | WALSIN TECHNOLOGY CORPORATION | WR04X2001FTL |  | 1 | 2 | 3 |  | G |  |  |  |  |  |  |  |
|  |  |  |  |  | 70 | 610114J00-011-G |  | RES,2KOhm,+/-1%,1/16W,G,SMD0402 | YAGEO CORPORATION COMPONENT | RC0402FR-072KL |  | 1 | 2 | 3 |  | G |  |  |  |  |  |  |  |
|  |  |  |  |  | 70 | 610114J00-044-G |  | RES,2KOhm,+/-1%,1/16W,G,SMD0402 | TA-I TECHNOLOGY CO., LTD | RM04FTN2001 | EVT | 1 | 2 | 3 |  | G |  |  |  |  |  |  |  |
|  |  |  |  |  | 70 | 610114J00-024-G |  | RES,2KOhm,+/-1%,1/16W,G,SMD0402 | PANASONIC INDUSTRIAL CO.,LTD. | ERJ2RKF2001X |  | 1 | 2 | 3 |  | G |  |  |  |  |  |  |  |
|  |  |  |  |  | 70 | 610114J00-029-G |  | RES,2KOhm,+/-1%,1/16W,G,SMD0402 | VISHAY ENTER TECHNO LOGY.INC | CRCW04022K00FKED |  | 1 | 2 | 3 |  | G |  |  |  |  |  |  |  |
| Multi | N | other | Y(4) | 71 | 71 | 610100T00-017-G |  | RES,1KOhm,+/-5%,1/16W,G,SMD0402 | KOA SPEER ELECTRONICS, INC. | RK73B1ETTP102J | EVT | 1 | 2 | 3 | 41 | G | R515,R517,R518,R519,R521,R522,R523,R524,R558,R561,R562,R564,R565,R566,R567,R1314,R1786,R1789,R1790,R1792,R1794,R1797,R1798,R1801,R1802,R1805,R1806,R1809,R1810,R1813,R1814,R1817,R1818,R1821,R1822,R1825,R1826,R1829,R1830,R2052,R2082 |  |  |  |  |  |  |
|  |  |  |  |  | 71 | 610100T00-012-G |  | RES,1KOhm,+/-5%,1/16W,G,SMD0402 | WALSIN TECHNOLOGY CORPORATION | WR04X102JTL |  | 1 | 2 | 3 |  | G |  |  |  |  |  |  |  |
|  |  |  |  |  | 71 | 610100T00-011-G |  | RES,1KOhm,+/-5%,1/16W,G,SMD0402 | YAGEO CORPORATION COMPONENT | RC0402JR-071KL |  | 1 | 2 | 3 |  | G |  |  |  |  |  |  |  |
|  |  |  |  |  | 71 | 610100T00-044-G |  | RES,1KOhm,+/-5%,1/16W,G,SMD0402 | TA-I TECHNOLOGY CO., LTD | RM04JTN102 |  | 1 | 2 | 3 |  | G |  |  |  |  |  |  |  |
|  |  |  |  |  | 71 | 610100T00-024-G |  | RES,1KOhm,+/-5%,1/16W,G,SMD0402 | PANASONIC INDUSTRIAL CO.,LTD. | ERJ2GEJ102X |  | 1 | 2 | 3 |  | G |  |  |  |  |  |  |  |
| Multi | N | ND | Y(4) | 72 | 72 | 61010L300-017-G | - | RES,1KOhm,+/-1%,1/16W,G,SMD0402 | KOA SPEER ELECTRONICS, INC. | RK73H1ETTP1001F | EVT | 1 | 2 | 3 | 10 | G | R525,R532,R865,R1072,R1073,R1074,R1077,R1438,R1439,R1440 |  |  |  |  |  |  |
|  |  |  |  |  | 72 | 61010L300-012-G |  | RES,1KOhm,+/-1%,1/16W,G,SMD0402 | WALSIN TECHNOLOGY CORPORATION | WR04X1001FTL |  | 1 | 2 | 3 |  | G |  |  |  |  |  |  |  |
|  |  |  |  |  | 72 | 61010L300-011-G |  | RES,1KOhm,+/-1%,1/16W,G,SMD0402 | YAGEO CORPORATION COMPONENT | RC0402FR-071KL |  | 1 | 2 | 3 |  | G |  |  |  |  |  |  |  |
|  |  |  |  |  | 72 | 61010L300-044-G |  | RES,1KOhm,+/-1%,1/16W,G,SMD0402 | TA-I TECHNOLOGY CO., LTD | RM04FTN1001 |  | 1 | 2 | 3 |  | G |  |  |  |  |  |  |  |
|  |  |  |  |  | 72 | 61010L300-024-G |  | RES,1KOhm,+/-1%,1/16W,G,SMD0402 | PANASONIC INDUSTRIAL CO.,LTD. | ERJ2RKF1001X |  | 1 | 2 | 3 |  | G |  |  |  |  |  |  |  |
|  |  |  |  |  | 72 | 61010L300-029-G |  | RES,1KOhm,+/-1%,1/16W,G,SMD0402 | VISHAY ENTER TECHNO LOGY.INC | CRCW04021K00FKED |  | 1 | 2 | 3 |  | G |  |  |  |  |  |  |  |
| Multi | ND | ND | N | 73 | 73 | 61010PS00-017-G | - | RES,200KOhm,+/-1%,1/16W,G,SMD0402 | KOA SPEER ELECTRONICS, INC. | RK73H1ETTP2003F |  | 1 | 2 | 3 | 2 | G | R526,R533 |  |  |  |  |  |  |
|  |  |  |  |  | 73 | 61010PS00-012-G |  | RES,200KOhm,+/-1%,1/16W,G,SMD0402 | WALSIN TECHNOLOGY CORPORATION | WR04X2003FTL | EVT | 1 | 2 | 3 |  | G |  |  |  |  |  |  |  |
|  |  |  |  |  | 73 | 61010PS00-011-G |  | RES,200KOhm,+/-1%,1/16W,G,SMD0402 | YAGEO CORPORATION COMPONENT | RC0402FR-07200KL |  | 1 | 2 | 3 |  | G |  |  |  |  |  |  |  |
|  |  |  |  |  | 73 | 61010PS00-044-G |  | RES,200KOhm,+/-1%,1/16W,G,SMD0402 | TA-I TECHNOLOGY CO., LTD | RM04FTN2003 |  | 1 | 2 | 3 |  | G |  |  |  |  |  |  |  |
| Multi | N | Other | N | 74 | 74 | 61011BW00-017-G |  | RES,1.2KOhm,+/-1%,1/16W,G,SMD0402 | KOA SPEER ELECTRONICS, INC. | RK73H1ETTP1201F |  | 1 | 2 | 3 | 2 | G | R529,R535 |  |  |  |  |  |  |
|  |  |  |  |  | 74 | 61011BW00-012-G |  | RES,1.2KOhm,+/-1%,1/16W,G,SMD0402 | WALSIN TECHNOLOGY CORPORATION | WR04X1201FTL |  | 1 | 2 | 3 |  | G |  |  |  |  |  |  |  |
|  |  |  |  |  | 74 | 61011BW00-011-G |  | RES,1.2KOhm,+/-1%,1/16W,G,SMD0402 | YAGEO CORPORATION COMPONENT | RC0402FR-071K2L | EVT | 1 | 2 | 3 |  | G |  |  |  |  |  |  |  |
|  |  |  |  |  | 74 | 61011BW00-044-G |  | RES,1.2KOhm,+/-1%,1/16W,G,SMD0402 | TA-I TECHNOLOGY CO., LTD | RM04FTN1201 |  | 1 | 2 | 3 |  | G |  |  |  |  |  |  |  |
| Multi | ND | ND | N | 75 | 75 | 610116V00-017-G | - | RES,232KOhm,+/-1%,1/16W,G,SMD0402 | KOA SPEER ELECTRONICS, INC. | RK73H1ETTP2323F |  | 1 | 2 | 3 | 1 | G | R530 |  |  |  |  |  |  |
|  |  |  |  |  | 75 | 610116V00-012-G |  | RES,232KOhm,+/-1%,1/16W,G,SMD0402 | WALSIN TECHNOLOGY CORPORATION | WR04X2323FTL |  | 1 | 2 | 3 |  | G |  |  |  |  |  |  |  |
|  |  |  |  |  | 75 | 610116V00-011-G |  | RES,232KOhm,+/-1%,1/16W,G,SMD0402 | YAGEO CORPORATION COMPONENT | RC0402FR-07232KL | EVT | 1 | 2 | 3 |  | G |  |  |  |  |  |  |  |
|  |  |  |  |  | 75 | 610116V00-044-G |  | RES,232KOhm,+/-1%,1/16W,G,SMD0402 | TA-I TECHNOLOGY CO., LTD | RM04FTN2323 |  | 1 | 2 | 3 |  | G |  |  |  |  |  |  |  |
| Multi | N | other | N | 76 | 76 | 610116B00-017-G |  | RES,180KOhm,+/-1%,1/16W,G,SMD0402 | KOA SPEER ELECTRONICS, INC. | RK73H1ETTP1803F |  | 1 | 2 | 3 | 1 | G | R534 |  |  |  |  |  |  |
|  |  |  |  |  | 76 | 610116B00-012-G |  | RES,180KOhm,+/-1%,1/16W,G,SMD0402 | WALSIN TECHNOLOGY CORPORATION | WR04X1803FTL | EVT | 1 | 2 | 3 |  | G |  |  |  |  |  |  |  |
|  |  |  |  |  | 76 | 610116B00-011-G |  | RES,180KOhm,+/-1%,1/16W,G,SMD0402 | YAGEO CORPORATION COMPONENT | RC0402FR-07180KL |  | 1 | 2 | 3 |  | G |  |  |  |  |  |  |  |
|  |  |  |  |  | 76 | 610116B00-044-G |  | RES,180KOhm,+/-1%,1/16W,G,SMD0402 | TA-I TECHNOLOGY CO., LTD | RM04FTN1803 |  | 1 | 2 | 3 |  | G |  |  |  |  |  |  |  |
| Multi | N | Other | N | 77 | 77 | 61011BQ00-017-G | - | RES,2.2 Ohm,+/-5%,1/16W,G,SMD0402 | KOA SPEER ELECTRONICS, INC. | RK73B1ETTP2R2J |  | 1 | 2 | 3 | 2 | G | R540,R583 |  |  |  |  |  |  |
|  |  |  |  |  | 77 | 61011BQ00-011-G |  | RES,2.2 Ohm,+/-5%,1/16W,G,SMD0402 | YAGEO CORPORATION COMPONENT | RC0402JR-072R2L |  | 1 | 2 | 3 |  | G |  |  |  |  |  |  |  |
|  |  |  |  |  | 77 | 61011BQ00-012-G |  | RES,2.2 Ohm,+/-5%,1/16W,G,SMD0402 | WALSIN TECHNOLOGY CORPORATION | WR04X2R2JTL | EVT | 1 | 2 | 3 |  | G |  |  |  |  |  |  |  |
|  |  |  |  |  | 77 | 61011BQ00-044-G |  | RES,2.2 Ohm,+/-5%,1/16W,G,SMD0402 | TA-I TECHNOLOGY CO., LTD | RM04JTN2R2 |  | 1 | 2 | 3 |  | G |  |  |  |  |  |  |  |
| Multi | N | ND | N | 78 | 78 | 610108300-017-G | - | RES,0 Ohm,+/-5%,1/10W,G,SMD0603 | KOA SPEER ELECTRONICS, INC. | RK73Z1JTTD |  | 1 | 2 | 3 | 2 | G | R542,R585 |  |  |  |  |  |  |
|  |  |  |  |  | 78 | 610108300-012-G |  | RES,0 Ohm,+/-5%,1/10W,G,SMD0603 | WALSIN TECHNOLOGY CORPORATION | WR06X000PTL |  | 1 | 2 | 3 |  | G |  |  |  |  |  |  |  |
|  |  |  |  |  | 78 | 610108300-011-G |  | RES,0 Ohm,+/-5%,1/10W,G,SMD0603 | YAGEO CORPORATION COMPONENT | RC0603JR-070RL | EVT | 1 | 2 | 3 |  | G |  |  |  |  |  |  |  |
|  |  |  |  |  | 78 | 610108300-044-G |  | RES,0 Ohm,+/-5%,1/10W,G,SMD0603 | TA-I TECHNOLOGY CO., LTD | RM06JTN0 |  | 1 | 2 | 3 |  | G |  |  |  |  |  |  |  |
|  |  |  |  |  | 78 | 610108300-024-G |  | RES,0 Ohm,+/-5%,1/10W,G,SMD0603 | PANASONIC INDUSTRIAL CO.,LTD. | ERJ3GEY0R00V |  | 1 | 2 | 3 |  | G |  |  |  |  |  |  |  |
| Multi | N | ND | Y(4) | 79 | 79 | 61010FE00-017-G | - | RES,100 Ohm,+/-1%,1/16W,G,SMD0402 | KOA SPEER ELECTRONICS, INC. | RK73H1ETTP1000F | EVT | 1 | 2 | 3 | 1 | G | R543 |  |  |  |  |  |  |
|  |  |  |  |  | 79 | 61010FE00-012-G |  | RES,100 Ohm,+/-1%,1/16W,G,SMD0402 | WALSIN TECHNOLOGY CORPORATION | WR04X1000FTL |  | 1 | 2 | 3 |  | G |  |  |  |  |  |  |  |
|  |  |  |  |  | 79 | 61010FE00-011-G |  | RES,100 Ohm,+/-1%,1/16W,G,SMD0402 | YAGEO CORPORATION COMPONENT | RC0402FR-07100RL |  | 1 | 2 | 3 |  | G |  |  |  |  |  |  |  |
|  |  |  |  |  | 79 | 61010FE00-044-G |  | RES,100 Ohm,+/-1%,1/16W,G,SMD0402 | TA-I TECHNOLOGY CO., LTD | RM04FTN1000 |  | 1 | 2 | 3 |  | G |  |  |  |  |  |  |  |
| Multi | ND | ND | Y(4) | 80 | 80 | 610118400-017-G |  | RES,27 Ohm,+/-1%,1/16W,G,SMD0402 | KOA SPEER ELECTRONICS, INC. | RK73H1ETTP27R0F |  | 1 | 2 | 3 | 32 | G | R817,R818,R828,R830,R832,R833,R834,R860,R867,R1443,R1444,R1445,R1446,R1447,R1448,R1458,R1459,R1460,R1461,R1462,R1463,R1464,R1465,R1466,R1467,R1468,R1469,R1470,R1471,R1472,R1473,R1604 |  |  |  |  |  |  |
|  |  |  |  |  | 80 | 610118400-012-G |  | RES,27 Ohm,+/-1%,1/16W,G,SMD0402 | WALSIN TECHNOLOGY CORPORATION | WR04X27R0FTL |  | 1 | 2 | 3 |  | G |  |  |  |  |  |  |  |
|  |  |  |  |  | 80 | 610118400-011-G |  | RES,27 Ohm,+/-1%,1/16W,G,SMD0402 | YAGEO CORPORATION COMPONENT | RC0402FR-0727RL | EVT | 1 | 2 | 3 |  | G |  |  |  |  |  |  |  |
|  |  |  |  |  | 80 | 610118400-044-G |  | RES,27 Ohm,+/-1%,1/16W,G,SMD0402 | TA-I TECHNOLOGY CO., LTD | RM04FTN27R0 |  | 1 | 2 | 3 |  | G |  |  |  |  |  |  |  |
| Multi | N | Other | N | 81 | 81 | 610113A00-017-G | - | RES,2.2 Ohm,+/-5%,1/2W,G,SMD1210 | KOA SPEER ELECTRONICS, INC. | RK73B2ETTD2R2J |  | 1 | 2 | 3 | 24 | G | R874,R876,R878,R880,R882,R884,R886,R888,R890,R892,R894,R896,R898,R900,R902,R904,R906,R908,R910,R912,R914,R916,R918,R920 |  |  |  |  |  |  |
|  |  |  |  |  | 81 | 610113A00-012-G |  | RES,2.2 Ohm,+/-5%,1/2W,G,SMD1210 | WALSIN TECHNOLOGY CORPORATION | WF10P2R2JTL |  | 1 | 2 | 3 |  | G |  |  |  |  |  |  |  |
|  |  |  |  |  | 81 | 610113A00-011-G |  | RES,2.2 Ohm,+/-5%,1/2W,G,SMD1210 | YAGEO CORPORATION COMPONENT | RC1210JR-072R2L | EVT | 1 | 2 | 3 |  | G |  |  |  |  |  |  |  |
| Multi | N |  | Y(4) | 82 | 82 | 61015K700-017-G |  | RES,3.3 Ohm,+/-5%,1/2W,G,SMD1210 | KOA SPEER ELECTRONICS, INC. | RK73B2ETTD3R3J | EVT | 1 | 2 | 3 | 24 | G | R875,R877,R879,R881,R883,R885,R887,R889,R891,R893,R895,R897,R899,R901,R903,R905,R907,R909,R911,R913,R915,R917,R919,R921 |  |  |  |  |  |  |
|  |  |  |  |  | 82 | 61015K700-011-G |  | RES,3.3 Ohm,+/-5%,1/2W,G,SMD1210 | YAGEO CORPORATION COMPONENT | RC1210JR-073R3L |  | 1 | 2 | 3 |  | G |  |  |  |  |  |  |  |
| Multi | ND | ND | Y(4) | 83 | 83 | 61011MV00-017-G |  | RES,510 Ohm,+/-1%,1/16W,G,SMD0402 | KOA SPEER ELECTRONICS, INC. | RK73H1ETTP5100F |  | 1 | 2 | 3 | 24 | G | R1313,R1785,R1787,R1788,R1791,R1793,R1795,R1796,R1799,R1800,R1803,R1804,R1807,R1808,R1811,R1812,R1815,R1816,R1819,R1820,R1823,R1824,R1827,R1828 |  |  |  |  |  |  |
|  |  |  |  |  | 83 | 61011MV00-012-G |  | RES,510 Ohm,+/-1%,1/16W,G,SMD0402 | WALSIN TECHNOLOGY CORPORATION | WR04X5100FTL |  | 1 | 2 | 3 |  | G |  |  |  |  |  |  |  |
|  |  |  |  |  | 83 | 61011MV00-011-G |  | RES,510 Ohm,+/-1%,1/16W,G,SMD0402 | YAGEO CORPORATION COMPONENT | RC0402FR-07510RL |  | 1 | 2 | 3 |  | G |  |  |  |  |  |  |  |
|  |  |  |  |  | 83 | 61011MV00-044-G |  | RES,510 Ohm,+/-1%,1/16W,G,SMD0402 | TA-I TECHNOLOGY CO., LTD | RM04FTN5100 |  | 1 | 2 | 3 |  | G |  |  |  |  |  |  |  |
| Multi |  |  | Y(4) | 84 | 84 | 610107L00-017-G |  | RES,1 Ohm,+/-5%,1/10W,G,SMD0603 | KOA SPEER ELECTRONICS, INC. | RK73B1JTTD1R0J | EVT | 1 | 2 | 3 | 2 | G | R1408,R1449 |  |  |  |  |  |  |
|  |  |  |  |  | 84 | 610107L00-011-G |  | RES,1 Ohm,+/-5%,1/10W,G,SMD0603 | YAGEO CORPORATION COMPONENT | RC0603JR-071RL |  | 1 | 2 | 3 |  | G |  |  |  |  |  |  |  |
|  |  |  |  |  | 84 | 610107L00-012-G |  | RES,1 Ohm,+/-5%,1/10W,G,SMD0603 | WALSIN TECHNOLOGY CORPORATION | WR06X1R0JTL |  | 1 | 2 | 3 |  | G |  |  |  |  |  |  |  |
|  |  |  |  |  | 84 | 610107L00-044-G |  | RES,1 Ohm,+/-5%,1/10W,G,SMD0603 | TA-I TECHNOLOGY CO., LTD | RM06JTN1R0 |  | 1 | 2 | 3 |  | G |  |  |  |  |  |  |  |
| Multi | ND | ND | Y(5) | 85 | 85 | 61100AH00-017-G |  | RES,10KOhm,+/-0.5%,1/16W,G,SMD0402 | KOA SPEER ELECTRONICS, INC. | RN731ETTP1002D25 | EVT | 1 |  |  | 12 | G | R2049,R2050,R2051,R2062,R2063,R2064,R2071,R2075,R2077,R2079,R2083,R2084 |  |  |  |  |  |  |
|  |  |  |  |  | 85 | 61100AH00-011-G |  | RES,10KOhm,+/-0.5%,1/16W,G,SMD0402 | YAGEO CORPORATION COMPONENT | RT0402DRE0710KL | EVT |  |  |  |  | G |  |  |  |  |  |  |  |
|  |  |  |  |  | 85 | 61100AH00-044-G |  | RES,10KOhm,+/-0.5%,1/16W,G,SMD0402 | TA-I TECHNOLOGY CO., LTD | RB04DTP1002 |  |  | 2 |  |  | G |  |  |  |  |  |  |  |
|  |  |  |  |  | 85 | 61100AH00-012-G |  | RES,10KOhm,+/-0.5%,1/16W,G,SMD0402 | WALSIN TECHNOLOGY CORPORATION | WF04U1002DTL |  |  |  | 3 |  | G |  |  |  |  |  |  |  |
| Multi | N |  | Y(4) | 86 | 86 | 610154800-017-G |  | RES,1 Ohm,+/-5%,1/8W,G,SMD0402 | KOA SPEER ELECTRONICS, INC. | SG73P1ETTP1R0J | EVT | 1 | 2 | 3 | 1 | G | R2060 |  |  |  |  |  |  |
|  |  |  |  |  | 86 | 610154800-011-G |  | RES,1 Ohm,+/-5%,1/8W,G,SMD0402 | YAGEO CORPORATION COMPONENT | RC0402JR-7W1RL |  | 1 | 2 | 3 |  | G |  |  |  |  |  |  |  |
|  |  |  |  |  | 86 | 610154800-012-G |  | RES,1 Ohm,+/-5%,1/8W,G,SMD0402 | WALSIN TECHNOLOGY CORPORATION | WF04P1R0 JTL |  | 1 | 2 | 3 |  | G |  |  |  |  |  |  |  |
| Multi | N | ND | Y(3) | 87 | 87 | 310101400-031-G | - | IC,Gate&Inverter,74LVC1G08GW,1.65~5.5V,G,SOT353-5,SMD | NXP SEMICONDUCTORS | 74LVC1G08GW | EVT | 1 |  |  | 3 | G | U_AND1,U_AND2,U5 |  |  |  |  |  |  |
|  |  |  |  |  | 87 | 310103J00-223-G |  | IC,Gate&Inverter,NL17SZ08DFT2G,1.65~5.5V,G,SOT353-5,SMD | ON SEMICONDUCTOR CORP | NL17SZ08DFT2G |  |  | 2 |  |  | G |  |  |  |  |  |  |  |
|  |  |  |  |  | 87 | 31010J400-131-G |  | IC,Gate&Inverter,TC7SZ08FU,1.8~5.5V,G,SSOP-5,SMD | TOSHIBA ELECTRONICS ASIA LTD | TC7SZ08FU |  |  |  | 3 |  | G |  |  |  |  |  |  |  |
| Multi | ND |  | N | 88 | 88 | 41040HW00-191-G |  | EEPROM,AT24C02D-SSHM-T,1.7~3.6V,2K,I2C,G,SOIC-8,SMD | ATMEL CORPORATION | AT24C02D-SSHM-T |  | 1 |  |  | 1 | G | U_BP_FRU1 |  |  |  |  |  |  |
|  |  |  |  |  | 88 | 410401W00-214-G |  | EEPROM,M24C02-WMN6TP,2.5~5.5V,256*8,I2C,G,SOIC-8,SMD | ST MICRO ELECTRONICS,INC | M24C02-WMN6TP |  |  | 2 |  |  | G |  |  |  |  |  |  |  |
|  |  |  |  |  | 88 | 41040J500-232-G |  | EEPROM,24AA024T-I/SN,1.7V~5.5V,2K,I2C,G,SOIC-8,SMD | MICROCHIP TECHNOLOGY INC | 24AA024T-I/SN |  |  |  | 3 |  | G |  |  |  |  |  |  |  |
| Single | ND | ND | Y(1) | 89 | 89 | 21050LL00-217-G | - | IC,IDT,9ZXL0831AKLFT,G,VFQFPN-48,SMD | INTEGRATED DEVICE TECHNOLOGY | 9ZXL0831AKLFT | EVT | 1 | 2 | 3 | 2 | G | U_Clock_B,U_Clock_A |  |  |  |  |  |  |
| Multi | ND | ND | N | 90 | 90 | 311004800-031-G | - | IC,Translator,PCA9617ADPJ,0.8~5.5V,2.2~5.5V,G,TSSOP-8,SMD | NXP SEMICONDUCTORS | PCA9617ADPJ |  |  | 2 |  | 2 | G | U_I2C_RE1,U_I2C_RE2 |  |  |  |  |  |  |
|  |  |  |  |  | 90 | 311004V00-223-G |  | Logic IC,Translator,PCA9617ADMR2G,Vcca=0.8V~5.5V,Vccb=2.2V~5.5V,102ns,Micro8,8P,G | ON SEMICONDUCTOR CORP | PCA9617ADMR2G | EVT | 1 |  | 3 |  | G |  |  |  |  |  |  |  |
| Multi | ND | ND | Y(2) | 91 | 91 | 31030CA00-031-G |  | IC,Switch,PCA9546APW,2.3~5.5V,G,TSSOP-16,SMD | NXP SEMICONDUCTORS | PCA9546APW |  |  | 2 |  | 5 | G | U_MUX1,U_MUX2,U_MUX3,U_MUX4,U_MUX5 |  |  |  |  |  |  |
|  |  |  |  |  | 91 | 31030YF00-252-G |  | Logic IC,Switch,PI4MSD5V9546ALEX,1.65V~5.5V,0.3ns,TSSOP,16P,G | PERICOM SEMICONDUCTOR CORP | PI4MSD5V9546ALEX | EVT | 1 |  | 3 |  | G |  |  |  |  |  |  |  |
| Single | ND |  | N | 92 | 92 | 32040P400-399-G |  | IC,Voltage sensor,SLG4N020VTR,G,TDFN-8,SMD | SILEGO | SLG4N020VTR |  | 1 | 2 | 3 | 1 | G | U_RESET |  |  |  |  |  |  |
| Single | ND |  | ND | 93 | 93 | 32022WB00-173-G |  | IC,Power Controller,MAX6420UK16+T,G,SOT-23-5P,SMD | MAXIM INTEGRATED PRODUCTS, INC. | MAX6420UK16+T | EVT | 1 | 2 | 3 | 1 | G | U_RESET1 |  |  |  |  |  |  |
| Single | Y |  | N | 94 | 94 | 21081NC00-432-G |  | IC,LSI,500021009,A2,G,TFBGA-141,SMD | LSI LOGIC CORPORATION | 500021009 |  | 1 | 2 | 3 | 2 | G | U_SF1,U_SF2 |  |  |  |  |  |  |
| Multi | N |  | N | 95 | 95 | 32040J800-183-G |  | IC,Temp Sensor,TMP75AIDGKR,N/A,G,MSOP-8,SMD | TEXAS INSTRUMENTS | TMP75AIDGKR | EVT | 1 |  | 3 | 1 | G | U_TMP1 |  |  |  |  |  |  |
|  |  |  |  |  | 95 | 32040PJ00-223-G |  | IC,Temperature Sensor,NCT75DMR2G,G,MSOP-8,SMD | ON SEMICONDUCTOR CORP | NCT75DMR2G |  |  | 2 |  |  | G |  |  |  |  |  |  |  |
| Multi | N | Other | N | 96 | 96 | 310700500-183-G |  | IC,Decoder&Encoder,PCA9306DCUR,0~5V,G,VSSOP-8,SMD | TEXAS INSTRUMENTS | PCA9306DCUR | EVT | 1 |  | 3 | 2 | G | U1,U2 |  |  |  |  |  |  |
|  |  |  |  |  | 96 | 311002900-031-G |  | IC,Translator,PCA9306DC1,1.0~3.6V,1.8~5.5V,G,VSSOP-8,SMD | NXP SEMICONDUCTORS | PCA9306DC1 |  |  | 2 |  |  | G |  |  |  |  |  |  |  |
| Single | ND |  | N | 97 | 97 | 21050RJ00-217-G |  | IC,IDT,9FGL0651BKILFT,G,VFQFPN-40,SMD | INTEGRATED DEVICE TECHNOLOGY | 9FGL0651BKILFT | EVT | 1 | 2 | 3 | 1 | G | U29 |  |  |  |  |  |  |
| Single | ND | ND | N | 98 | 98 | 310501200-183-G | - | IC,Buffer,SN74LVC1G07DCKR,1.65~5.5V,G,SC70-5,SMD | TEXAS INSTRUMENTS | SN74LVC1G07DCKR | EVT | 1 | 2 | 3 | 1 | G | U209 |  |  |  |  |  |  |
| Single | Y |  | Y(2) | 99 | 99 | 220106A00-413-G |  | IC,PLD,10M08SCU169C8G,3.3V,116MHz,G,BGA-169,SMD | ALTERA CORPORATION | 10M08SCU169C8G |  | 1 | 2 | 3 | 1 | G | U248 |  |  |  |  |  |  |
| Single | ND |  | N | 100 | 100 | 71012HD00-100-G |  | XTAL,25MHz,+/-20ppm,8pF,G,SMD | TXC CORPORATION | 7V25000054 | EVT | 1 | 2 | 3 | 1 | G | X7 |  |  |  |  |  |  |
| Single | N |  | N | 101 | 101 | 2A5910Q00-HYM-G |  | SMT NUT,CARBON STEEL,G,FIVETECH,82-059-01-022-01-RL | Fivetech Technology Inc. | 82-059-01-022-01-RL | EVT | 1 | 2 | 3 | 10 | G | H1,H2,H3,H4,H7,H8,H9,H10,H30,H31 |  |  |  |  |  |  |
| Multi | Y |  | N | 102 | 102 | 340718A00-245-G |  | CONN,SAS,V/T,0.6mm,30u,G,SMD-74 | AMPHENOL SHANGHAI CORP. | U10-B074-250T | EVT | 1 |  | 3 | 10 | G | JSAS1,JPCIE1,JSAS2,JPCIE2,JSAS3,JPCIE3,JPCIE4,JPCIE5,JPCIE6,JPCIE7 |  |  |  |  |  |  |
|  |  |  |  |  | 102 | U10-B274-250T |  | CONN,SAS,V/T,0.6mm,30u,G,SMD-74 | AMPHENOL SHANGHAI CORP. | U10-B274-250T |  |  | 2 |  |  | G |  |  |  |  |  |  |  |
| Single | ND |  | N | 103 | 103 | 3406B6F00-317-G |  | CONN,Header,WTB,2X3,R/A,Bla,2.5mm,15u,G,SMD-6 | MOLEX INCORPORATED | 15-91-2065 | EVT | 1 | 2 | 3 | 1 | G | J_CPLD_JTAG |  |  |  |  |  |  |
| Multi | ND | ND | N | 104 | 104 | 340655900-245-G | - | CONN,Header,WTB,1X4,R/A,Whi,1mm,G,SMD-4 | AMPHENOL SHANGHAI CORP. | G846A04100Y1EU | EVT | 1 |  | 3 | 1 | G | J_LED1 |  |  |  |  |  |  |
|  |  |  |  |  | 104 | 34066NA00-32M-G |  | Header&Socket Connector,80012-0427,Wire-to-Board Header,4,SMD,THERMOPLASTIC,1mm,100u",Nature,G | BELLWETHER ELECTRONIC CORP. | 80012-0427 |  |  | 2 |  |  | G |  |  |  |  |  |  |  |
| Multi | ND | ND | N | 105 | 105 | 340313H00-600-G | - | CONN,PCIE,V/T,Bla,0.8mm,30u,G,SMD-68 | FOXCONN TECHNOLOGY CO.,LTD. | LU25683-A001-9H | EVT | 1 |  | 3 | 24 | G | J_NVME01,J_NVME02,J_NVME03,J_NVME04,J_NVME05,J_NVME06,J_NVME07,J_NVME08,J_NVME09,J_NVME10,J_NVME11,J_NVME12,J_NVME13,J_NVME14,J_NVME15,J_NVME16,J_NVME17,J_NVME18,J_NVME19,J_NVME20,J_NVME21,J_NVME22,J_NVME23,J_NVME00 |  |  |  |  |  |  |
|  |  |  |  |  | 105 | 34031BQ00-317-G |  | CONN,PCIE,V/T,Bla,0.8mm,30u,G,SMD-68 | MOLEX INCORPORATED | 78777-1002 |  |  | 2 |  |  | G |  |  |  |  |  |  |  |
| Single | ND |  | N | 106 | 106 | 3406B3H00-317-G |  | CONN,Header,Power,2X8,V/T,Bla,3mm,G,SMD-16 | MOLEX INCORPORATED | 43045-1618 | EVT | 1 | 2 | 3 | 1 | G | J1 |  |  |  |  |  |  |
